FILE_TYPE = MACRO_DRAWING;
SET COLOR_WIRE YELLOW;
SET COLOR_PROP MONO;
SET COLOR_DOT WHITE;
SET COLOR_ARC YELLOW;
SET COLOR_BODY GREEN;
SET COLOR_NOTE MONO;
SET PROP_DISPLAY VALUE;
SET PAGE_NUMBER P204;
FORCEADD OFFPAGE..2
(-1425 4575);
FORCEPROP 2 LAST $XR0 201 
J 0
(-1236 4575);
DISPLAY 0.638298 (-1236 4575);
PAINT MONO (-1236 4575);
FORCEPROP 2 LAST BOM_COST PROC_VRD_VCCIN_CPU0
J 0
(-1225 4625);
DISPLAY 1.446809 (-1225 4625);
PAINT MONO (-1225 4625);
DISPLAY INVISIBLE (-1225 4625);
FORCEPROP 2 LAST PATH I1
J 0
(-1220 4625);
DISPLAY 1.021277 (-1220 4625);
PAINT ORANGE (-1220 4625);
DISPLAY INVISIBLE (-1220 4625);
FORCEPROP 2 LAST CDS_LIB mstr_standard
J 2
(-1425 4575);
DISPLAY 1.936170 (-1425 4575);
PAINT ORANGE (-1425 4575);
DISPLAY INVISIBLE (-1425 4575);
FORCEPROP 1 LAST OFFPAGE TRUE
J 0
(-1100 4450);
DISPLAY 1.723404 (-1100 4450);
PAINT GREEN (-1100 4450);
DISPLAY INVISIBLE (-1100 4450);
FORCEPROP 1 LAST COMMENT_BODY TRUE
J 0
(-1470 4480);
DISPLAY 1.723404 (-1470 4480);
PAINT GREEN (-1470 4480);
DISPLAY INVISIBLE (-1470 4480);
FORCEPROP 2 LAST ROOM PVCCIN_CPU0_PWR_VR
J 0
(-1825 4650);
DISPLAY 1.936170 (-1825 4650);
PAINT ORANGE (-1825 4650);
DISPLAY INVISIBLE (-1825 4650);
FORCEADD GND..1
(-2850 3050);
FORCEPROP 3 LASTPIN (-2850 3100) SIG_NAME GND\g
J 0
(-2840 3110);
DISPLAY 0.659574 (-2840 3110);
PAINT MONO (-2840 3110);
DISPLAY INVISIBLE (-2840 3110);
FORCEPROP 1 LAST HDL_POWER GND
J 0
(-2850 3200);
DISPLAY 1.723404 (-2850 3200);
PAINT GREEN (-2850 3200);
DISPLAY INVISIBLE (-2850 3200);
FORCEPROP 1 LAST VOLTAGE 0
J 0
(-2850 3050);
PAINT SKYBLUE (-2850 3050);
DISPLAY INVISIBLE (-2850 3050);
FORCEPROP 2 LAST CDS_LIB mstr_symbols
J 0
(-2850 3050);
DISPLAY 1.936170 (-2850 3050);
PAINT ORANGE (-2850 3050);
DISPLAY INVISIBLE (-2850 3050);
FORCEPROP 1 LAST PATH I13
J 0
(-2775 3050);
DISPLAY 0.872340 (-2775 3050);
PAINT AQUA (-2775 3050);
DISPLAY INVISIBLE (-2775 3050);
FORCEPROP 1 LAST SIZE 1B
J 0
(-2775 3000);
DISPLAY 1.723404 (-2775 3000);
PAINT GREEN (-2775 3000);
DISPLAY INVISIBLE (-2775 3000);
FORCEPROP 1 LAST BODY_TYPE PLUMBING
J 0
(-2895 3007);
DISPLAY 0.340426 (-2895 3007);
PAINT GREEN (-2895 3007);
DISPLAY INVISIBLE (-2895 3007);
FORCEPROP 2 LAST BOM_COST PROC_VRD_VCCIN_CPU0
J 0
(-3225 3125);
DISPLAY 1.446809 (-3225 3125);
PAINT MONO (-3225 3125);
DISPLAY INVISIBLE (-3225 3125);
FORCEPROP 2 LAST ROOM PVCCIN_CPU0_PWR_VR
J 0
(-3400 3125);
DISPLAY 1.936170 (-3400 3125);
PAINT ORANGE (-3400 3125);
DISPLAY INVISIBLE (-3400 3125);
FORCEADD CAP..1
(-5675 3975);
FORCEPROP 1 LASTPIN (-5675 3875) $PN 2
J 0
(-5665 3855);
DISPLAY 0.617021 (-5665 3855);
PAINT ORANGE (-5665 3855);
FORCEPROP 1 LASTPIN (-5675 4075) $PN 1
J 0
(-5665 4055);
DISPLAY 0.617021 (-5665 4055);
PAINT ORANGE (-5665 4055);
FORCEPROP 1 LAST VOLTAGE 16V
J 0
(-5625 3975);
DISPLAY 0.617021 (-5625 3975);
PAINT SKYBLUE (-5625 3975);
FORCEPROP 1 LAST VALUE 0.22UF
J 0
(-5625 4025);
DISPLAY 0.617021 (-5625 4025);
PAINT SKYBLUE (-5625 4025);
FORCEPROP 1 LAST TOLERANCE 10%
J 0
(-5625 3925);
DISPLAY 0.617021 (-5625 3925);
PAINT SKYBLUE (-5625 3925);
FORCEPROP 1 LAST PACK_TYPE 0402
J 0
(-5625 3775);
DISPLAY 0.617021 (-5625 3775);
PAINT SKYBLUE (-5625 3775);
FORCEPROP 1 LAST LOCATION C4D47
J 0
(-5625 4075);
DISPLAY 0.617021 (-5625 4075);
PAINT AQUA (-5625 4075);
FORCEPROP 1 LAST MATERIAL X7R
J 0
(-5625 3875);
DISPLAY 0.617021 (-5625 3875);
PAINT SKYBLUE (-5625 3875);
FORCEPROP 1 LAST PART_NUMBER A36096-155
J 0
(-5625 3825);
DISPLAY 0.617021 (-5625 3825);
PAINT BLUE (-5625 3825);
FORCEPROP 2 LAST SEC 1
J 0
(-5625 4175);
DISPLAY 0.680851 (-5625 4175);
PAINT MONO (-5625 4175);
DISPLAY INVISIBLE (-5625 4175);
FORCEPROP 1 LAST PATH I18
J 0
(-5625 4125);
DISPLAY 0.978723 (-5625 4125);
PAINT WHITE (-5625 4125);
DISPLAY INVISIBLE (-5625 4125);
FORCEPROP 2 LAST ROOM PVCCIN_CPU0_PWR_VR
J 0
(-5625 4125);
DISPLAY 1.361702 (-5625 4125);
PAINT ORANGE (-5625 4125);
DISPLAY INVISIBLE (-5625 4125);
FORCEPROP 2 LAST SEC_TYPE 0402
J 0
(-5625 4175);
DISPLAY 1.021277 (-5625 4175);
PAINT ORANGE (-5625 4175);
DISPLAY INVISIBLE (-5625 4175);
FORCEPROP 2 LAST CDS_LIB mstr_discrete
J 0
(-5675 3975);
PAINT ORANGE (-5675 3975);
DISPLAY INVISIBLE (-5675 3975);
FORCEADD CAP_A..1
R 2
(-5825 3975);
FORCEPROP 1 LAST PART_NUMBER D97712-004
J 2
(-5875 3825);
DISPLAY 0.617021 (-5875 3825);
PAINT BLUE (-5875 3825);
FORCEPROP 1 LAST PACK_TYPE 0402V
J 2
(-5875 3775);
DISPLAY 0.617021 (-5875 3775);
PAINT SKYBLUE (-5875 3775);
FORCEPROP 1 LAST VALUE 1.0UF
J 2
(-5875 4025);
DISPLAY 0.617021 (-5875 4025);
PAINT SKYBLUE (-5875 4025);
FORCEPROP 1 LAST TOLERANCE 10%
J 2
(-5875 3925);
DISPLAY 0.617021 (-5875 3925);
PAINT SKYBLUE (-5875 3925);
FORCEPROP 1 LAST VOLTAGE 6.3V
J 2
(-5875 3975);
DISPLAY 0.617021 (-5875 3975);
PAINT SKYBLUE (-5875 3975);
FORCEPROP 1 LAST MATERIAL X6S
J 2
(-5875 3875);
DISPLAY 0.617021 (-5875 3875);
PAINT SKYBLUE (-5875 3875);
FORCEPROP 1 LASTPIN (-5825 3875) $PN 2
J 2
(-5835 3855);
DISPLAY 0.617021 (-5835 3855);
PAINT ORANGE (-5835 3855);
FORCEPROP 1 LASTPIN (-5825 4075) $PN 1
J 2
(-5835 4055);
DISPLAY 0.617021 (-5835 4055);
PAINT ORANGE (-5835 4055);
FORCEPROP 1 LAST LOCATION C4C14
J 2
(-5875 4075);
DISPLAY 0.617021 (-5875 4075);
PAINT AQUA (-5875 4075);
FORCEPROP 2 LAST ROOM PVCCIN_CPU0_PWR_VR
J 0
(-5875 4125);
DISPLAY 1.361702 (-5875 4125);
PAINT ORANGE (-5875 4125);
DISPLAY INVISIBLE (-5875 4125);
FORCEPROP 1 LAST PATH I19
J 2
(-5875 4125);
DISPLAY 0.978723 (-5875 4125);
PAINT WHITE (-5875 4125);
DISPLAY INVISIBLE (-5875 4125);
FORCEPROP 2 LAST SEC 1
J 0
(-5875 4175);
DISPLAY 0.680851 (-5875 4175);
PAINT MONO (-5875 4175);
DISPLAY INVISIBLE (-5875 4175);
FORCEPROP 2 LAST SEC_TYPE 0402V
J 0
(-5875 4175);
DISPLAY 1.021277 (-5875 4175);
PAINT ORANGE (-5875 4175);
DISPLAY INVISIBLE (-5875 4175);
FORCEPROP 2 LAST CDS_SEC 1
J 0
(-5875 4125);
PAINT ORANGE (-5875 4125);
DISPLAY INVISIBLE (-5875 4125);
FORCEPROP 2 LAST CDS_LOCATION C4C14
J 2
(-5875 4075);
DISPLAY 0.617021 (-5875 4075);
PAINT AQUA (-5875 4075);
DISPLAY INVISIBLE (-5875 4075);
FORCEPROP 2 LAST CDS_LIB dev_discrete
J 0
(-5825 3975);
PAINT ORANGE (-5825 3975);
DISPLAY INVISIBLE (-5825 3975);
FORCEADD OFFPAGE..2
(-1450 4250);
FORCEPROP 2 LAST $XR0 201 
J 0
(-1261 4250);
DISPLAY 0.638298 (-1261 4250);
PAINT MONO (-1261 4250);
FORCEPROP 2 LAST BOM_COST PROC_VRD_VCCIN_CPU0
J 0
(-1250 4300);
DISPLAY 1.446809 (-1250 4300);
PAINT MONO (-1250 4300);
DISPLAY INVISIBLE (-1250 4300);
FORCEPROP 1 LAST OFFPAGE TRUE
J 0
(-1125 4125);
DISPLAY 1.723404 (-1125 4125);
PAINT GREEN (-1125 4125);
DISPLAY INVISIBLE (-1125 4125);
FORCEPROP 2 LAST PATH I2
J 0
(-1245 4300);
DISPLAY 1.021277 (-1245 4300);
PAINT ORANGE (-1245 4300);
DISPLAY INVISIBLE (-1245 4300);
FORCEPROP 2 LAST CDS_LIB mstr_standard
J 0
(-1450 4250);
DISPLAY 1.936170 (-1450 4250);
PAINT ORANGE (-1450 4250);
DISPLAY INVISIBLE (-1450 4250);
FORCEPROP 1 LAST COMMENT_BODY TRUE
J 0
(-1495 4155);
DISPLAY 1.723404 (-1495 4155);
PAINT GREEN (-1495 4155);
DISPLAY INVISIBLE (-1495 4155);
FORCEPROP 2 LAST ROOM PVCCIN_CPU0_PWR_VR
J 0
(-1850 4325);
DISPLAY 1.936170 (-1850 4325);
PAINT ORANGE (-1850 4325);
DISPLAY INVISIBLE (-1850 4325);
FORCEADD CAP..1
R 2
(-6200 3350);
FORCEPROP 1 LAST PART_NUMBER A36096-104
J 2
(-6250 3200);
DISPLAY 0.617021 (-6250 3200);
PAINT BLUE (-6250 3200);
FORCEPROP 1 LASTPIN (-6200 3450) $PN 1
J 2
(-6210 3430);
DISPLAY 0.617021 (-6210 3430);
PAINT ORANGE (-6210 3430);
FORCEPROP 1 LAST MATERIAL X7R
J 2
(-6250 3250);
DISPLAY 0.617021 (-6250 3250);
PAINT SKYBLUE (-6250 3250);
FORCEPROP 1 LASTPIN (-6200 3250) $PN 2
J 2
(-6210 3230);
DISPLAY 0.617021 (-6210 3230);
PAINT ORANGE (-6210 3230);
FORCEPROP 1 LAST TOLERANCE 10%
J 2
(-6250 3300);
DISPLAY 0.617021 (-6250 3300);
PAINT SKYBLUE (-6250 3300);
FORCEPROP 1 LAST VOLTAGE 16V
J 2
(-6250 3350);
DISPLAY 0.617021 (-6250 3350);
PAINT SKYBLUE (-6250 3350);
FORCEPROP 1 LAST VALUE 0.220UF
J 2
(-6250 3400);
DISPLAY 0.617021 (-6250 3400);
PAINT SKYBLUE (-6250 3400);
FORCEPROP 1 LAST LOCATION C4C17
J 2
(-6250 3450);
DISPLAY 0.617021 (-6250 3450);
PAINT AQUA (-6250 3450);
FORCEPROP 1 LAST PACK_TYPE 0402
J 2
(-6250 3150);
DISPLAY 0.617021 (-6250 3150);
PAINT SKYBLUE (-6250 3150);
FORCEPROP 2 LAST ROOM PVCCIN_CPU0_PWR_VR
J 0
(-6275 3500);
DISPLAY 1.361702 (-6275 3500);
PAINT ORANGE (-6275 3500);
DISPLAY INVISIBLE (-6275 3500);
FORCEPROP 1 LAST PATH I22
J 2
(-6250 3500);
DISPLAY 0.978723 (-6250 3500);
PAINT WHITE (-6250 3500);
DISPLAY INVISIBLE (-6250 3500);
FORCEPROP 2 LAST CDS_LOCATION C4C17
J 2
(-6250 3450);
DISPLAY 0.617021 (-6250 3450);
PAINT AQUA (-6250 3450);
DISPLAY INVISIBLE (-6250 3450);
FORCEPROP 2 LAST SEC 1
J 0
(-6250 3550);
DISPLAY 0.680851 (-6250 3550);
PAINT MONO (-6250 3550);
DISPLAY INVISIBLE (-6250 3550);
FORCEPROP 2 LAST CDS_LIB mstr_discrete
J 0
(-6200 3350);
PAINT ORANGE (-6200 3350);
DISPLAY INVISIBLE (-6200 3350);
FORCEPROP 0 LAST SPOF TRUE
J 0
(-6250 3550);
DISPLAY 1.021277 (-6250 3550);
PAINT ORANGE (-6250 3550);
DISPLAY INVISIBLE (-6250 3550);
FORCEPROP 2 LAST SEC_TYPE 0402
J 0
(-6250 3550);
DISPLAY 1.021277 (-6250 3550);
PAINT ORANGE (-6250 3550);
DISPLAY INVISIBLE (-6250 3550);
FORCEPROP 2 LAST NO_XNET_CONNECTION 1
J 0
(-6250 3550);
PAINT MONO (-6250 3550);
DISPLAY INVISIBLE (-6250 3550);
FORCEADD OFFPAGE..2
(-1875 3900);
FORCEPROP 2 LAST $XR0 202 
J 0
(-1686 3900);
DISPLAY 0.638298 (-1686 3900);
PAINT MONO (-1686 3900);
FORCEPROP 2 LAST $XR1 203 
J 0
(-1566 3900);
DISPLAY 0.638298 (-1566 3900);
PAINT MONO (-1566 3900);
FORCEPROP 2 LAST $XR2 201 
J 0
(-1446 3900);
DISPLAY 0.638298 (-1446 3900);
PAINT MONO (-1446 3900);
FORCEPROP 2 LAST ROOM PVCCIN_CPU0_PWR_VR
J 0
(-2275 3975);
DISPLAY 1.936170 (-2275 3975);
PAINT ORANGE (-2275 3975);
DISPLAY INVISIBLE (-2275 3975);
FORCEPROP 1 LAST COMMENT_BODY TRUE
J 0
(-1920 3805);
DISPLAY 1.723404 (-1920 3805);
PAINT GREEN (-1920 3805);
DISPLAY INVISIBLE (-1920 3805);
FORCEPROP 2 LAST CDS_LIB mstr_standard
J 0
(-1875 3900);
PAINT ORANGE (-1875 3900);
DISPLAY INVISIBLE (-1875 3900);
FORCEPROP 2 LAST PATH I3
J 0
(-1695 3975);
DISPLAY 1.021277 (-1695 3975);
PAINT ORANGE (-1695 3975);
DISPLAY INVISIBLE (-1695 3975);
FORCEPROP 1 LAST OFFPAGE TRUE
J 0
(-1550 3775);
DISPLAY 1.723404 (-1550 3775);
PAINT GREEN (-1550 3775);
DISPLAY INVISIBLE (-1550 3775);
FORCEPROP 2 LAST BOM_COST PROC_VRD_VCCIN_CPU0
J 0
(-1675 3950);
DISPLAY 1.446809 (-1675 3950);
PAINT MONO (-1675 3950);
DISPLAY INVISIBLE (-1675 3950);
FORCEADD RES..1
(-6100 4525);
FORCEPROP 1 LAST VALUE 1.0
J 2
(-6200 4400);
DISPLAY 0.617021 (-6200 4400);
PAINT SKYBLUE (-6200 4400);
FORCEPROP 1 LASTPIN (-6200 4525) $PN 1
J 0
(-6188 4537);
DISPLAY 0.617021 (-6188 4537);
PAINT ORANGE (-6188 4537);
FORCEPROP 1 LAST LOCATION R6P47
J 0
(-6150 4575);
DISPLAY 0.617021 (-6150 4575);
PAINT AQUA (-6150 4575);
FORCEPROP 1 LAST PART_NUMBER G21796-090
J 0
(-6225 4450);
DISPLAY 0.617021 (-6225 4450);
PAINT BLUE (-6225 4450);
FORCEPROP 1 LAST TOLERANCE 1%
J 0
(-6150 4400);
DISPLAY 0.617021 (-6150 4400);
PAINT SKYBLUE (-6150 4400);
FORCEPROP 1 LAST WATTAGE 1/16W
J 2
(-6075 4350);
DISPLAY 0.617021 (-6075 4350);
PAINT SKYBLUE (-6075 4350);
FORCEPROP 1 LAST PACK_TYPE 0402
J 0
(-6050 4400);
DISPLAY 0.617021 (-6050 4400);
PAINT SKYBLUE (-6050 4400);
FORCEPROP 1 LAST MATERIAL CHIP
J 0
(-6025 4350);
DISPLAY 0.617021 (-6025 4350);
PAINT SKYBLUE (-6025 4350);
FORCEPROP 1 LASTPIN (-6000 4525) $PN 2
J 0
(-6038 4537);
DISPLAY 0.617021 (-6038 4537);
PAINT ORANGE (-6038 4537);
FORCEPROP 2 LAST CDS_LIB mstr_discrete
J 0
(-6100 4525);
PAINT ORANGE (-6100 4525);
DISPLAY INVISIBLE (-6100 4525);
FORCEPROP 2 LAST ROOM PVCCIN_CPU0_PWR_VR
J 0
(-6150 4625);
DISPLAY 1.361702 (-6150 4625);
PAINT ORANGE (-6150 4625);
DISPLAY INVISIBLE (-6150 4625);
FORCEPROP 1 LAST PATH I33
J 0
(-6150 4675);
DISPLAY 0.978723 (-6150 4675);
PAINT WHITE (-6150 4675);
DISPLAY INVISIBLE (-6150 4675);
FORCEPROP 2 LAST SEC 1
J 0
(-6150 4725);
DISPLAY 0.680851 (-6150 4725);
PAINT MONO (-6150 4725);
DISPLAY INVISIBLE (-6150 4725);
FORCEPROP 2 LAST SEC_TYPE 0402
J 0
(-6150 4725);
DISPLAY 1.021277 (-6150 4725);
PAINT ORANGE (-6150 4725);
DISPLAY INVISIBLE (-6150 4725);
FORCEADD CAP..1
(-6425 3950);
FORCEPROP 1 LASTPIN (-6425 3850) $PN 2
J 0
(-6415 3830);
DISPLAY 0.617021 (-6415 3830);
PAINT ORANGE (-6415 3830);
FORCEPROP 1 LASTPIN (-6425 4050) $PN 1
J 0
(-6415 4030);
DISPLAY 0.617021 (-6415 4030);
PAINT ORANGE (-6415 4030);
FORCEPROP 1 LAST LOCATION C4D46
J 0
(-6375 4050);
DISPLAY 0.617021 (-6375 4050);
PAINT AQUA (-6375 4050);
FORCEPROP 1 LAST VALUE 1.0UF
J 0
(-6375 4000);
DISPLAY 0.617021 (-6375 4000);
PAINT SKYBLUE (-6375 4000);
FORCEPROP 1 LAST TOLERANCE 10%
J 0
(-6375 3900);
DISPLAY 0.617021 (-6375 3900);
PAINT SKYBLUE (-6375 3900);
FORCEPROP 1 LAST PACK_TYPE 0402
J 0
(-6375 3750);
DISPLAY 0.617021 (-6375 3750);
PAINT SKYBLUE (-6375 3750);
FORCEPROP 1 LAST VOLTAGE 16V
J 0
(-6375 3950);
DISPLAY 0.617021 (-6375 3950);
PAINT SKYBLUE (-6375 3950);
FORCEPROP 1 LAST MATERIAL X6S
J 0
(-6375 3850);
DISPLAY 0.617021 (-6375 3850);
PAINT SKYBLUE (-6375 3850);
FORCEPROP 1 LAST PART_NUMBER D97712-011
J 0
(-6375 3800);
DISPLAY 0.617021 (-6375 3800);
PAINT BLUE (-6375 3800);
FORCEPROP 2 LAST SEC_TYPE 0402
J 0
(-6375 4150);
DISPLAY 1.021277 (-6375 4150);
PAINT ORANGE (-6375 4150);
DISPLAY INVISIBLE (-6375 4150);
FORCEPROP 2 LAST SEC 1
J 0
(-6375 4150);
DISPLAY 0.680851 (-6375 4150);
PAINT MONO (-6375 4150);
DISPLAY INVISIBLE (-6375 4150);
FORCEPROP 1 LAST PATH I34
J 0
(-6375 4100);
DISPLAY 0.978723 (-6375 4100);
PAINT WHITE (-6375 4100);
DISPLAY INVISIBLE (-6375 4100);
FORCEPROP 2 LAST ROOM PVCCIN_CPU0_PWR_VR
J 0
(-6375 4100);
DISPLAY 1.361702 (-6375 4100);
PAINT ORANGE (-6375 4100);
DISPLAY INVISIBLE (-6375 4100);
FORCEPROP 2 LAST CDS_LIB mstr_discrete
J 0
(-6425 3950);
PAINT ORANGE (-6425 3950);
DISPLAY INVISIBLE (-6425 3950);
FORCEADD CAP_A..1
(-6650 3975);
FORCEPROP 1 LAST PACK_TYPE 0402V
J 0
(-6600 3775);
DISPLAY 0.617021 (-6600 3775);
PAINT SKYBLUE (-6600 3775);
FORCEPROP 1 LASTPIN (-6650 4075) $PN 1
J 0
(-6640 4055);
DISPLAY 0.617021 (-6640 4055);
PAINT ORANGE (-6640 4055);
FORCEPROP 1 LASTPIN (-6650 3875) $PN 2
J 0
(-6640 3855);
DISPLAY 0.617021 (-6640 3855);
PAINT ORANGE (-6640 3855);
FORCEPROP 1 LAST VOLTAGE 16V
J 0
(-6600 3975);
DISPLAY 0.617021 (-6600 3975);
PAINT SKYBLUE (-6600 3975);
FORCEPROP 1 LAST MATERIAL X7R
J 0
(-6600 3875);
DISPLAY 0.617021 (-6600 3875);
PAINT SKYBLUE (-6600 3875);
FORCEPROP 1 LAST TOLERANCE 10%
J 0
(-6600 3925);
DISPLAY 0.617021 (-6600 3925);
PAINT SKYBLUE (-6600 3925);
FORCEPROP 1 LAST VALUE 0.1UF
J 0
(-6600 4025);
DISPLAY 0.617021 (-6600 4025);
PAINT SKYBLUE (-6600 4025);
FORCEPROP 1 LAST PART_NUMBER A36096-030
J 0
(-6600 3825);
DISPLAY 0.617021 (-6600 3825);
PAINT BLUE (-6600 3825);
FORCEPROP 1 LAST LOCATION C4C19
J 0
(-6600 4075);
DISPLAY 0.617021 (-6600 4075);
PAINT AQUA (-6600 4075);
FORCEPROP 1 LAST PATH I35
J 0
(-6600 4125);
DISPLAY 0.978723 (-6600 4125);
PAINT WHITE (-6600 4125);
DISPLAY INVISIBLE (-6600 4125);
FORCEPROP 2 LAST ROOM PVCCIN_CPU0_PWR_VR
J 0
(-6600 4125);
DISPLAY 1.361702 (-6600 4125);
PAINT ORANGE (-6600 4125);
DISPLAY INVISIBLE (-6600 4125);
FORCEPROP 2 LAST CDS_SEC 1
J 0
(-6600 4125);
PAINT ORANGE (-6600 4125);
DISPLAY INVISIBLE (-6600 4125);
FORCEPROP 2 LAST SEC_TYPE 0402V
J 0
(-6600 4175);
DISPLAY 1.021277 (-6600 4175);
PAINT ORANGE (-6600 4175);
DISPLAY INVISIBLE (-6600 4175);
FORCEPROP 2 LAST SEC 1
J 0
(-6600 4175);
DISPLAY 0.680851 (-6600 4175);
PAINT MONO (-6600 4175);
DISPLAY INVISIBLE (-6600 4175);
FORCEPROP 2 LAST CDS_LIB dev_discrete
J 0
(-6650 3975);
PAINT ORANGE (-6650 3975);
DISPLAY INVISIBLE (-6650 3975);
FORCEADD CAP..1
(-6875 3925);
FORCEPROP 1 LASTPIN (-6875 3825) $PN 2
J 0
(-6865 3805);
DISPLAY 0.617021 (-6865 3805);
PAINT ORANGE (-6865 3805);
FORCEPROP 1 LAST PACK_TYPE 0402
J 0
(-6825 3725);
DISPLAY 0.617021 (-6825 3725);
PAINT SKYBLUE (-6825 3725);
FORCEPROP 1 LAST MATERIAL X6S
J 0
(-6825 3825);
DISPLAY 0.617021 (-6825 3825);
PAINT SKYBLUE (-6825 3825);
FORCEPROP 1 LAST LOCATION C4C18
J 0
(-6825 4025);
DISPLAY 0.617021 (-6825 4025);
PAINT AQUA (-6825 4025);
FORCEPROP 1 LAST VALUE 1.0UF
J 0
(-6825 3975);
DISPLAY 0.617021 (-6825 3975);
PAINT SKYBLUE (-6825 3975);
FORCEPROP 1 LAST TOLERANCE 10%
J 0
(-6825 3875);
DISPLAY 0.617021 (-6825 3875);
PAINT SKYBLUE (-6825 3875);
FORCEPROP 1 LAST VOLTAGE 16V
J 0
(-6825 3925);
DISPLAY 0.617021 (-6825 3925);
PAINT SKYBLUE (-6825 3925);
FORCEPROP 1 LASTPIN (-6875 4025) $PN 1
J 0
(-6865 4005);
DISPLAY 0.617021 (-6865 4005);
PAINT ORANGE (-6865 4005);
FORCEPROP 1 LAST PART_NUMBER D97712-011
J 0
(-6825 3775);
DISPLAY 0.617021 (-6825 3775);
PAINT BLUE (-6825 3775);
FORCEPROP 2 LAST SEC_TYPE 0402
J 0
(-6825 4125);
DISPLAY 1.021277 (-6825 4125);
PAINT ORANGE (-6825 4125);
DISPLAY INVISIBLE (-6825 4125);
FORCEPROP 2 LAST SEC 1
J 0
(-6825 4125);
DISPLAY 0.680851 (-6825 4125);
PAINT MONO (-6825 4125);
DISPLAY INVISIBLE (-6825 4125);
FORCEPROP 1 LAST PATH I36
J 0
(-6825 4075);
DISPLAY 0.978723 (-6825 4075);
PAINT WHITE (-6825 4075);
DISPLAY INVISIBLE (-6825 4075);
FORCEPROP 2 LAST ROOM PVCCIN_CPU0_PWR_VR
J 0
(-6825 4075);
DISPLAY 1.361702 (-6825 4075);
PAINT ORANGE (-6825 4075);
DISPLAY INVISIBLE (-6825 4075);
FORCEPROP 2 LAST CDS_LIB mstr_discrete
J 0
(-6875 3925);
PAINT ORANGE (-6875 3925);
DISPLAY INVISIBLE (-6875 3925);
FORCEADD CAP..1
(-7100 3975);
FORCEPROP 1 LAST PACK_TYPE 0805
J 0
(-7050 3775);
DISPLAY 0.617021 (-7050 3775);
PAINT SKYBLUE (-7050 3775);
FORCEPROP 1 LAST VALUE 10UF
J 0
(-7050 4025);
DISPLAY 0.617021 (-7050 4025);
PAINT SKYBLUE (-7050 4025);
FORCEPROP 1 LAST TOLERANCE 10%
J 0
(-7050 3925);
DISPLAY 0.617021 (-7050 3925);
PAINT SKYBLUE (-7050 3925);
FORCEPROP 1 LAST VOLTAGE 16V
J 0
(-7050 3975);
DISPLAY 0.617021 (-7050 3975);
PAINT SKYBLUE (-7050 3975);
FORCEPROP 1 LAST MATERIAL X6S
J 0
(-7050 3875);
DISPLAY 0.617021 (-7050 3875);
PAINT SKYBLUE (-7050 3875);
FORCEPROP 1 LASTPIN (-7100 3875) $PN 2
J 0
(-7090 3855);
DISPLAY 0.617021 (-7090 3855);
PAINT ORANGE (-7090 3855);
FORCEPROP 1 LASTPIN (-7100 4075) $PN 1
J 0
(-7090 4055);
DISPLAY 0.617021 (-7090 4055);
PAINT ORANGE (-7090 4055);
FORCEPROP 1 LAST PART_NUMBER C95333-007
J 0
(-7050 3825);
DISPLAY 0.617021 (-7050 3825);
PAINT BLUE (-7050 3825);
FORCEPROP 1 LAST LOCATION C6N10
J 0
(-7050 4075);
DISPLAY 0.617021 (-7050 4075);
PAINT AQUA (-7050 4075);
FORCEPROP 2 LAST SEC_TYPE 0805
J 0
(-7050 4175);
DISPLAY 1.021277 (-7050 4175);
PAINT ORANGE (-7050 4175);
DISPLAY INVISIBLE (-7050 4175);
FORCEPROP 2 LAST SEC 1
J 0
(-7050 4175);
DISPLAY 0.680851 (-7050 4175);
PAINT MONO (-7050 4175);
DISPLAY INVISIBLE (-7050 4175);
FORCEPROP 1 LAST PATH I37
J 0
(-7050 4125);
DISPLAY 0.978723 (-7050 4125);
PAINT WHITE (-7050 4125);
DISPLAY INVISIBLE (-7050 4125);
FORCEPROP 2 LAST ROOM PVCCIN_CPU0_PWR_VR
J 0
(-7050 4125);
DISPLAY 1.361702 (-7050 4125);
PAINT ORANGE (-7050 4125);
DISPLAY INVISIBLE (-7050 4125);
FORCEPROP 2 LAST CDS_LIB mstr_discrete
J 0
(-7100 3975);
PAINT ORANGE (-7100 3975);
DISPLAY INVISIBLE (-7100 3975);
FORCEADD CAP..1
(-7325 3925);
FORCEPROP 1 LAST PACK_TYPE 0805
J 0
(-7275 3725);
DISPLAY 0.617021 (-7275 3725);
PAINT SKYBLUE (-7275 3725);
FORCEPROP 1 LAST PART_NUMBER C95333-007
J 0
(-7275 3775);
DISPLAY 0.617021 (-7275 3775);
PAINT BLUE (-7275 3775);
FORCEPROP 1 LASTPIN (-7325 3825) $PN 2
J 0
(-7315 3805);
DISPLAY 0.617021 (-7315 3805);
PAINT ORANGE (-7315 3805);
FORCEPROP 1 LAST MATERIAL X6S
J 0
(-7275 3825);
DISPLAY 0.617021 (-7275 3825);
PAINT SKYBLUE (-7275 3825);
FORCEPROP 1 LAST TOLERANCE 10%
J 0
(-7275 3875);
DISPLAY 0.617021 (-7275 3875);
PAINT SKYBLUE (-7275 3875);
FORCEPROP 1 LAST VOLTAGE 16V
J 0
(-7275 3925);
DISPLAY 0.617021 (-7275 3925);
PAINT SKYBLUE (-7275 3925);
FORCEPROP 1 LASTPIN (-7325 4025) $PN 1
J 0
(-7315 4005);
DISPLAY 0.617021 (-7315 4005);
PAINT ORANGE (-7315 4005);
FORCEPROP 1 LAST LOCATION C6P17
J 0
(-7275 4025);
DISPLAY 0.617021 (-7275 4025);
PAINT AQUA (-7275 4025);
FORCEPROP 1 LAST VALUE 10UF
J 0
(-7275 3975);
DISPLAY 0.617021 (-7275 3975);
PAINT SKYBLUE (-7275 3975);
FORCEPROP 2 LAST SEC 1
J 0
(-7275 4125);
DISPLAY 0.680851 (-7275 4125);
PAINT MONO (-7275 4125);
DISPLAY INVISIBLE (-7275 4125);
FORCEPROP 2 LAST SEC_TYPE 0805
J 0
(-7275 4125);
DISPLAY 1.021277 (-7275 4125);
PAINT ORANGE (-7275 4125);
DISPLAY INVISIBLE (-7275 4125);
FORCEPROP 1 LAST PATH I38
J 0
(-7275 4075);
DISPLAY 0.978723 (-7275 4075);
PAINT WHITE (-7275 4075);
DISPLAY INVISIBLE (-7275 4075);
FORCEPROP 2 LAST ROOM PVCCIN_CPU0_PWR_VR
J 0
(-7275 4075);
DISPLAY 1.361702 (-7275 4075);
PAINT ORANGE (-7275 4075);
DISPLAY INVISIBLE (-7275 4075);
FORCEPROP 2 LAST CDS_LOCATION C6P17
J 0
(-7275 4025);
DISPLAY 0.617021 (-7275 4025);
PAINT AQUA (-7275 4025);
DISPLAY INVISIBLE (-7275 4025);
FORCEPROP 2 LAST CDS_LIB mstr_discrete
J 0
(-7325 3925);
PAINT ORANGE (-7325 3925);
DISPLAY INVISIBLE (-7325 3925);
FORCEADD PVCCIN_CPU0..1
(-775 3500);
FORCEPROP 3 LASTPIN (-775 3450) SIG_NAME PVCCIN_CPU0\g
J 0
(-765 3460);
DISPLAY 0.659574 (-765 3460);
PAINT MONO (-765 3460);
DISPLAY INVISIBLE (-765 3460);
FORCEPROP 1 LAST HDL_POWER PVCCIN_CPU0
J 1
(-775 3550);
DISPLAY 0.872340 (-775 3550);
PAINT GREEN (-775 3550);
DISPLAY INVISIBLE (-775 3550);
FORCEPROP 1 LAST PATH I4
J 0
(-725 3525);
DISPLAY 0.872340 (-725 3525);
PAINT AQUA (-725 3525);
DISPLAY INVISIBLE (-725 3525);
FORCEPROP 2 LAST CDS_LIB mstr_symbols
J 0
(-775 3500);
PAINT ORANGE (-775 3500);
DISPLAY INVISIBLE (-775 3500);
FORCEPROP 1 LAST VOLTAGE 2.0V
J 0
(-820 3457);
DISPLAY 0.340426 (-820 3457);
PAINT SKYBLUE (-820 3457);
DISPLAY INVISIBLE (-820 3457);
FORCEPROP 1 LAST BODY_TYPE PLUMBING
J 0
(-820 3457);
DISPLAY 0.340426 (-820 3457);
PAINT GREEN (-820 3457);
DISPLAY INVISIBLE (-820 3457);
FORCEADD OFFPAGE..1
(-6825 3600);
FORCEPROP 2 LAST $XR0 201 
J 0
(-7077 3600);
DISPLAY 0.638298 (-7077 3600);
PAINT MONO (-7077 3600);
FORCEPROP 2 LASTPIN (-6775 3600) SIG_NAME VR_PVCCIN_CPU0_PWM5
J 0
(-6760 3610);
DISPLAY 0.617021 (-6760 3610);
PAINT ORANGE (-6760 3610);
FORCEPROP 1 LAST OFFPAGE TRUE
J 0
(-6500 3475);
DISPLAY 1.680851 (-6500 3475);
PAINT GREEN (-6500 3475);
DISPLAY INVISIBLE (-6500 3475);
FORCEPROP 2 LAST CDS_LIB mstr_standard
J 0
(-6825 3600);
DISPLAY 1.936170 (-6825 3600);
PAINT ORANGE (-6825 3600);
DISPLAY INVISIBLE (-6825 3600);
FORCEPROP 2 LAST PATH I40
J 0
(-7095 3650);
DISPLAY 1.021277 (-7095 3650);
PAINT ORANGE (-7095 3650);
DISPLAY INVISIBLE (-7095 3650);
FORCEPROP 2 LAST BOM_COST PROC_VRD_VCCIN_CPU0
J 0
(-7075 3650);
DISPLAY 1.446809 (-7075 3650);
PAINT MONO (-7075 3650);
DISPLAY INVISIBLE (-7075 3650);
FORCEPROP 1 LAST COMMENT_BODY TRUE
J 0
(-6700 3500);
DISPLAY 1.680851 (-6700 3500);
PAINT GREEN (-6700 3500);
DISPLAY INVISIBLE (-6700 3500);
FORCEPROP 2 LAST ROOM PVCCIN_CPU0_PWR_VR
J 0
(-7225 3675);
DISPLAY 1.936170 (-7225 3675);
PAINT ORANGE (-7225 3675);
DISPLAY INVISIBLE (-7225 3675);
FORCEADD VCC_CORE..1
(-7550 4300);
FORCEPROP 3 LASTPIN (-7550 4250) SIG_NAME VR_FET_SW_P12V_STBY_PVCCIN_CPU0\g
J 0
(-7540 4260);
DISPLAY 0.659574 (-7540 4260);
PAINT MONO (-7540 4260);
DISPLAY INVISIBLE (-7540 4260);
FORCEPROP 1 LAST HDL_POWER VR_FET_SW_P12V_STBY_PVCCIN_CPU0
J 1
(-7475 4350);
DISPLAY 0.617021 (-7475 4350);
PAINT GREEN (-7475 4350);
FORCEPROP 1 LAST PATH I41
J 0
(-7500 4325);
DISPLAY 0.872340 (-7500 4325);
PAINT AQUA (-7500 4325);
DISPLAY INVISIBLE (-7500 4325);
FORCEPROP 2 LAST CDS_LIB mstr_symbols
J 0
(-7550 4300);
DISPLAY 1.936170 (-7550 4300);
PAINT ORANGE (-7550 4300);
DISPLAY INVISIBLE (-7550 4300);
FORCEADD CAP..1
(-7550 3950);
FORCEPROP 1 LAST PART_NUMBER C95333-007
J 0
(-7500 3800);
DISPLAY 0.617021 (-7500 3800);
PAINT BLUE (-7500 3800);
FORCEPROP 1 LASTPIN (-7550 3850) $PN 2
J 0
(-7540 3830);
DISPLAY 0.617021 (-7540 3830);
PAINT ORANGE (-7540 3830);
FORCEPROP 1 LASTPIN (-7550 4050) $PN 1
J 0
(-7540 4030);
DISPLAY 0.617021 (-7540 4030);
PAINT ORANGE (-7540 4030);
FORCEPROP 1 LAST LOCATION C6N11
J 0
(-7500 4050);
DISPLAY 0.617021 (-7500 4050);
PAINT AQUA (-7500 4050);
FORCEPROP 1 LAST VALUE 10UF
J 0
(-7500 4000);
DISPLAY 0.617021 (-7500 4000);
PAINT SKYBLUE (-7500 4000);
FORCEPROP 1 LAST TOLERANCE 10%
J 0
(-7500 3900);
DISPLAY 0.617021 (-7500 3900);
PAINT SKYBLUE (-7500 3900);
FORCEPROP 1 LAST PACK_TYPE 0805
J 0
(-7500 3750);
DISPLAY 0.617021 (-7500 3750);
PAINT SKYBLUE (-7500 3750);
FORCEPROP 1 LAST VOLTAGE 16V
J 0
(-7500 3950);
DISPLAY 0.617021 (-7500 3950);
PAINT SKYBLUE (-7500 3950);
FORCEPROP 1 LAST MATERIAL X6S
J 0
(-7500 3850);
DISPLAY 0.617021 (-7500 3850);
PAINT SKYBLUE (-7500 3850);
FORCEPROP 2 LAST SEC_TYPE 0805
J 0
(-7500 4150);
DISPLAY 1.021277 (-7500 4150);
PAINT ORANGE (-7500 4150);
DISPLAY INVISIBLE (-7500 4150);
FORCEPROP 2 LAST SEC 1
J 0
(-7500 4150);
DISPLAY 0.680851 (-7500 4150);
PAINT MONO (-7500 4150);
DISPLAY INVISIBLE (-7500 4150);
FORCEPROP 1 LAST PATH I42
J 0
(-7500 4100);
DISPLAY 0.978723 (-7500 4100);
PAINT WHITE (-7500 4100);
DISPLAY INVISIBLE (-7500 4100);
FORCEPROP 2 LAST ROOM PVCCIN_CPU0_PWR_VR
J 0
(-7500 4100);
DISPLAY 1.361702 (-7500 4100);
PAINT ORANGE (-7500 4100);
DISPLAY INVISIBLE (-7500 4100);
FORCEPROP 2 LAST CDS_LIB mstr_discrete
J 0
(-7550 3950);
PAINT ORANGE (-7550 3950);
DISPLAY INVISIBLE (-7550 3950);
FORCEADD GND..1
(-7550 3550);
FORCEPROP 3 LASTPIN (-7550 3600) SIG_NAME GND\g
J 0
(-7540 3610);
DISPLAY 0.659574 (-7540 3610);
PAINT MONO (-7540 3610);
DISPLAY INVISIBLE (-7540 3610);
FORCEPROP 1 LAST HDL_POWER GND
J 0
(-7550 3700);
DISPLAY 1.723404 (-7550 3700);
PAINT GREEN (-7550 3700);
DISPLAY INVISIBLE (-7550 3700);
FORCEPROP 1 LAST VOLTAGE 0
J 0
(-7550 3550);
PAINT SKYBLUE (-7550 3550);
DISPLAY INVISIBLE (-7550 3550);
FORCEPROP 2 LAST CDS_LIB mstr_symbols
J 0
(-7550 3550);
DISPLAY 1.936170 (-7550 3550);
PAINT ORANGE (-7550 3550);
DISPLAY INVISIBLE (-7550 3550);
FORCEPROP 1 LAST PATH I43
J 0
(-7475 3550);
DISPLAY 0.872340 (-7475 3550);
PAINT AQUA (-7475 3550);
DISPLAY INVISIBLE (-7475 3550);
FORCEPROP 1 LAST SIZE 1B
J 0
(-7475 3500);
DISPLAY 1.723404 (-7475 3500);
PAINT GREEN (-7475 3500);
DISPLAY INVISIBLE (-7475 3500);
FORCEPROP 1 LAST BODY_TYPE PLUMBING
J 0
(-7595 3507);
DISPLAY 0.340426 (-7595 3507);
PAINT GREEN (-7595 3507);
DISPLAY INVISIBLE (-7595 3507);
FORCEPROP 2 LAST BOM_COST PROC_VRD_VCCIN_CPU0
J 0
(-7925 3625);
DISPLAY 1.446809 (-7925 3625);
PAINT MONO (-7925 3625);
DISPLAY INVISIBLE (-7925 3625);
FORCEPROP 2 LAST ROOM PVCCIN_CPU0_PWR_VR
J 0
(-8100 3625);
DISPLAY 1.936170 (-8100 3625);
PAINT ORANGE (-8100 3625);
DISPLAY INVISIBLE (-8100 3625);
FORCEADD VCC_CORE..1
(-575 2450);
FORCEPROP 3 LASTPIN (-575 2400) SIG_NAME VR_FET_SW_P12V_STBY_PVCCIN_CPU0\g
J 0
(-565 2410);
DISPLAY 0.659574 (-565 2410);
PAINT MONO (-565 2410);
DISPLAY INVISIBLE (-565 2410);
FORCEPROP 1 LAST HDL_POWER VR_FET_SW_P12V_STBY_PVCCIN_CPU0
J 1
(-575 2500);
DISPLAY 0.617021 (-575 2500);
PAINT GREEN (-575 2500);
FORCEPROP 2 LAST CDS_LIB mstr_symbols
J 0
(-575 2450);
PAINT ORANGE (-575 2450);
DISPLAY INVISIBLE (-575 2450);
FORCEPROP 1 LAST PATH I44
J 0
(-525 2475);
DISPLAY 0.872340 (-525 2475);
PAINT AQUA (-525 2475);
DISPLAY INVISIBLE (-525 2475);
FORCEADD RES..1
(-1825 2175);
FORCEPROP 1 LAST PACK_TYPE 2010
J 0
(-1575 2025);
DISPLAY 0.617021 (-1575 2025);
PAINT SKYBLUE (-1575 2025);
FORCEPROP 1 LAST MATERIAL CHIP
J 0
(-1825 2025);
DISPLAY 0.617021 (-1825 2025);
PAINT SKYBLUE (-1825 2025);
FORCEPROP 1 LAST WATTAGE 1W
J 2
(-1850 2025);
DISPLAY 0.617021 (-1850 2025);
PAINT SKYBLUE (-1850 2025);
FORCEPROP 1 LAST VALUE 0.001
J 2
(-1850 2075);
DISPLAY 0.617021 (-1850 2075);
PAINT SKYBLUE (-1850 2075);
FORCEPROP 1 LASTPIN (-1925 2175) $PN 1
J 0
(-1913 2187);
DISPLAY 0.617021 (-1913 2187);
PAINT ORANGE (-1913 2187);
FORCEPROP 1 LAST PART_NUMBER E30969-002
J 0
(-1875 2275);
DISPLAY 0.617021 (-1875 2275);
PAINT BLUE (-1875 2275);
FORCEPROP 1 LAST LOCATION R4C6
J 0
(-1875 2225);
DISPLAY 0.617021 (-1875 2225);
PAINT AQUA (-1875 2225);
FORCEPROP 1 LAST TOLERANCE 1%
J 0
(-1825 2075);
DISPLAY 0.617021 (-1825 2075);
PAINT SKYBLUE (-1825 2075);
FORCEPROP 1 LASTPIN (-1725 2175) $PN 2
J 0
(-1763 2187);
DISPLAY 0.617021 (-1763 2187);
PAINT ORANGE (-1763 2187);
FORCEPROP 1 LAST PATH I45
J 0
(-1875 2325);
DISPLAY 0.978723 (-1875 2325);
PAINT WHITE (-1875 2325);
DISPLAY INVISIBLE (-1875 2325);
FORCEPROP 2 LAST SEC 1
J 0
(-1875 2375);
DISPLAY 0.680851 (-1875 2375);
PAINT MONO (-1875 2375);
DISPLAY INVISIBLE (-1875 2375);
FORCEPROP 2 LAST SEC_TYPE 2010
J 0
(-1875 2375);
DISPLAY 1.021277 (-1875 2375);
PAINT ORANGE (-1875 2375);
DISPLAY INVISIBLE (-1875 2375);
FORCEPROP 2 LAST ROOM PVCCIN_CPU0_FILTER_VR
J 0
(-1875 2275);
DISPLAY 1.361702 (-1875 2275);
PAINT ORANGE (-1875 2275);
DISPLAY INVISIBLE (-1875 2275);
FORCEPROP 2 LAST CDS_LOCATION R4C6
J 0
(-1875 2225);
DISPLAY 0.617021 (-1875 2225);
PAINT AQUA (-1875 2225);
DISPLAY INVISIBLE (-1875 2225);
FORCEPROP 2 LAST CDS_LIB mstr_discrete
J 0
(-1825 2175);
PAINT ORANGE (-1825 2175);
DISPLAY INVISIBLE (-1825 2175);
FORCEADD INDUCTOR..1
(-2975 2175);
FORCEPROP 1 LAST VALUE 100NH
J 2
(-2980 2040);
DISPLAY 0.617021 (-2980 2040);
PAINT SKYBLUE (-2980 2040);
FORCEPROP 1 LAST PACK_TYPE SM
J 0
(-2785 2040);
DISPLAY 0.617021 (-2785 2040);
PAINT SKYBLUE (-2785 2040);
FORCEPROP 1 LAST MATERIAL IND
J 0
(-2935 2040);
DISPLAY 0.617021 (-2935 2040);
PAINT SKYBLUE (-2935 2040);
FORCEPROP 1 LAST LOCATION L4C1
J 0
(-3075 2225);
DISPLAY 0.617021 (-3075 2225);
PAINT AQUA (-3075 2225);
FORCEPROP 1 LAST PART_NUMBER D92183-019
J 0
(-3125 2100);
DISPLAY 0.617021 (-3125 2100);
PAINT BLUE (-3125 2100);
FORCEPROP 1 LASTPIN (-3075 2175) $PN 1
J 0
(-3075 2185);
DISPLAY 0.617021 (-3075 2185);
PAINT WHITE (-3075 2185);
FORCEPROP 1 LASTPIN (-2875 2175) $PN 2
J 2
(-2865 2185);
DISPLAY 0.617021 (-2865 2185);
PAINT WHITE (-2865 2185);
FORCEPROP 2 LAST CDS_LIB mstr_discrete
J 0
(-2975 2175);
PAINT ORANGE (-2975 2175);
DISPLAY INVISIBLE (-2975 2175);
FORCEPROP 1 LAST PATH I46
J 0
(-3075 2325);
DISPLAY 0.978723 (-3075 2325);
PAINT ORANGE (-3075 2325);
DISPLAY INVISIBLE (-3075 2325);
FORCEPROP 2 LAST SEC 1
J 0
(-3075 2375);
DISPLAY 0.680851 (-3075 2375);
PAINT MONO (-3075 2375);
DISPLAY INVISIBLE (-3075 2375);
FORCEPROP 2 LAST SEC_TYPE SM
J 0
(-3075 2375);
DISPLAY 1.021277 (-3075 2375);
PAINT ORANGE (-3075 2375);
DISPLAY INVISIBLE (-3075 2375);
FORCEPROP 2 LAST ROOM PVCCIN_CPU0_FILTER_VR
J 0
(-3075 2275);
DISPLAY 1.361702 (-3075 2275);
PAINT ORANGE (-3075 2275);
DISPLAY INVISIBLE (-3075 2275);
FORCEPROP 2 LAST CDS_LOCATION L4C1
J 0
(-3075 2225);
DISPLAY 0.617021 (-3075 2225);
PAINT AQUA (-3075 2225);
DISPLAY INVISIBLE (-3075 2225);
FORCEADD CAPP..1
(-925 1975);
FORCEPROP 1 LASTPIN (-925 1875) $PN 2
J 0
(-915 1860);
DISPLAY 0.617021 (-915 1860);
PAINT ORANGE (-915 1860);
FORCEPROP 1 LAST TOLERANCE 20%
J 0
(-875 1975);
DISPLAY 0.617021 (-875 1975);
PAINT SKYBLUE (-875 1975);
FORCEPROP 1 LAST VOLTAGE 16V
J 0
(-875 1925);
DISPLAY 0.617021 (-875 1925);
PAINT SKYBLUE (-875 1925);
FORCEPROP 1 LAST PART_NUMBER A31228-047
J 0
(-875 1775);
DISPLAY 0.617021 (-875 1775);
PAINT BLUE (-875 1775);
FORCEPROP 1 LAST PACK_TYPE 2626
J 0
(-875 1825);
DISPLAY 0.617021 (-875 1825);
PAINT SKYBLUE (-875 1825);
FORCEPROP 1 LAST MATERIAL OSCON
J 0
(-875 1875);
DISPLAY 0.617021 (-875 1875);
PAINT SKYBLUE (-875 1875);
FORCEPROP 1 LAST VALUE 270UF
J 0
(-875 2025);
DISPLAY 0.617021 (-875 2025);
PAINT SKYBLUE (-875 2025);
FORCEPROP 1 LASTPIN (-925 2075) $PN 1
J 0
(-915 2060);
DISPLAY 0.617021 (-915 2060);
PAINT ORANGE (-915 2060);
FORCEPROP 1 LAST LOCATION C4D2
J 0
(-875 2075);
DISPLAY 0.617021 (-875 2075);
PAINT AQUA (-875 2075);
FORCEPROP 2 LAST SEC_TYPE 2626
J 0
(-875 2175);
DISPLAY 1.021277 (-875 2175);
PAINT ORANGE (-875 2175);
DISPLAY INVISIBLE (-875 2175);
FORCEPROP 2 LAST SEC 1
J 0
(-875 2175);
DISPLAY 0.680851 (-875 2175);
PAINT MONO (-875 2175);
DISPLAY INVISIBLE (-875 2175);
FORCEPROP 2 LAST CDS_LOCATION C4D2
J 0
(-875 2075);
DISPLAY 0.617021 (-875 2075);
PAINT AQUA (-875 2075);
DISPLAY INVISIBLE (-875 2075);
FORCEPROP 1 LAST PATH I48
J 0
(-875 2125);
DISPLAY 0.978723 (-875 2125);
PAINT ORANGE (-875 2125);
DISPLAY INVISIBLE (-875 2125);
FORCEPROP 2 LAST ROOM PVCCIN_CPU0_FILTER_VR
J 0
(-875 2125);
DISPLAY 1.361702 (-875 2125);
PAINT ORANGE (-875 2125);
DISPLAY INVISIBLE (-875 2125);
FORCEPROP 2 LAST CDS_LIB mstr_discrete
J 0
(-925 1975);
PAINT ORANGE (-925 1975);
DISPLAY INVISIBLE (-925 1975);
FORCEADD GND..1
(-1175 1575);
FORCEPROP 3 LASTPIN (-1175 1625) SIG_NAME GND\g
J 0
(-1165 1635);
DISPLAY 0.659574 (-1165 1635);
PAINT MONO (-1165 1635);
DISPLAY INVISIBLE (-1165 1635);
FORCEPROP 1 LAST PATH I49
J 0
(-1100 1575);
DISPLAY 0.872340 (-1100 1575);
PAINT AQUA (-1100 1575);
DISPLAY INVISIBLE (-1100 1575);
FORCEPROP 1 LAST HDL_POWER GND
J 0
(-1175 1725);
DISPLAY 0.893617 (-1175 1725);
PAINT GREEN (-1175 1725);
DISPLAY INVISIBLE (-1175 1725);
FORCEPROP 2 LAST CDS_LIB mstr_symbols
J 0
(-1175 1575);
PAINT ORANGE (-1175 1575);
DISPLAY INVISIBLE (-1175 1575);
FORCEPROP 1 LAST VOLTAGE 0
J 0
(-1175 1575);
PAINT SKYBLUE (-1175 1575);
DISPLAY INVISIBLE (-1175 1575);
FORCEPROP 1 LAST SIZE 1B
J 0
(-1100 1525);
DISPLAY 0.893617 (-1100 1525);
PAINT GREEN (-1100 1525);
DISPLAY INVISIBLE (-1100 1525);
FORCEPROP 1 LAST BODY_TYPE PLUMBING
J 0
(-1220 1532);
DISPLAY 0.340426 (-1220 1532);
PAINT GREEN (-1220 1532);
DISPLAY INVISIBLE (-1220 1532);
FORCEPROP 2 LAST BOM_COST PROC_VRD_VCCIN_CPU0
J 0
(-1550 1650);
PAINT MONO (-1550 1650);
DISPLAY INVISIBLE (-1550 1650);
FORCEPROP 2 LAST ROOM PVCCIN_CPU0_FILTER_VR
J 0
(-1725 1650);
PAINT ORANGE (-1725 1650);
DISPLAY INVISIBLE (-1725 1650);
FORCEADD INDUCTOR..1
(-1925 3400);
FORCEPROP 1 LAST PART_NUMBER D92183-034
J 0
(-2050 3350);
DISPLAY 0.617021 (-2050 3350);
PAINT BLUE (-2050 3350);
FORCEPROP 1 LAST PACK_TYPE SM
J 0
(-1760 3290);
DISPLAY 0.617021 (-1760 3290);
PAINT SKYBLUE (-1760 3290);
FORCEPROP 1 LAST VALUE 0.12UH
J 2
(-1930 3290);
DISPLAY 0.617021 (-1930 3290);
PAINT SKYBLUE (-1930 3290);
FORCEPROP 1 LASTPIN (-2025 3400) $PN 1
J 0
(-2025 3410);
DISPLAY 0.617021 (-2025 3410);
PAINT WHITE (-2025 3410);
FORCEPROP 1 LAST LOCATION L4C3
J 0
(-2025 3450);
DISPLAY 0.617021 (-2025 3450);
PAINT AQUA (-2025 3450);
FORCEPROP 1 LASTPIN (-1825 3400) $PN 2
J 2
(-1815 3410);
DISPLAY 0.617021 (-1815 3410);
PAINT WHITE (-1815 3410);
FORCEPROP 1 LAST MATERIAL IND
J 0
(-1885 3290);
DISPLAY 0.617021 (-1885 3290);
PAINT SKYBLUE (-1885 3290);
FORCEPROP 2 LAST CDS_SEC 1
J 0
(-2025 3600);
PAINT MONO (-2025 3600);
DISPLAY INVISIBLE (-2025 3600);
FORCEPROP 2 LAST $SEC 1
J 0
(-2025 3600);
PAINT MONO (-2025 3600);
DISPLAY INVISIBLE (-2025 3600);
FORCEPROP 1 LAST PATH I5
J 0
(-2025 3550);
DISPLAY 0.978723 (-2025 3550);
PAINT ORANGE (-2025 3550);
DISPLAY INVISIBLE (-2025 3550);
FORCEPROP 2 LAST ROOM PVCCIN_CPU0_PWR_VR
J 0
(-2025 3500);
DISPLAY 1.361702 (-2025 3500);
PAINT ORANGE (-2025 3500);
DISPLAY INVISIBLE (-2025 3500);
FORCEPROP 2 LAST CDS_LOCATION L4C3
J 0
(-2025 3450);
DISPLAY 0.617021 (-2025 3450);
PAINT AQUA (-2025 3450);
DISPLAY INVISIBLE (-2025 3450);
FORCEPROP 2 LAST CDS_LIB mstr_discrete
J 0
(-1925 3400);
PAINT ORANGE (-1925 3400);
DISPLAY INVISIBLE (-1925 3400);
FORCEADD CAPP..1
(-1400 2000);
FORCEPROP 1 LASTPIN (-1400 1900) $PN 2
J 0
(-1390 1885);
DISPLAY 0.617021 (-1390 1885);
PAINT ORANGE (-1390 1885);
FORCEPROP 1 LAST PART_NUMBER A31228-047
J 0
(-1350 1800);
DISPLAY 0.617021 (-1350 1800);
PAINT BLUE (-1350 1800);
FORCEPROP 1 LAST TOLERANCE 20%
J 0
(-1350 2000);
DISPLAY 0.617021 (-1350 2000);
PAINT SKYBLUE (-1350 2000);
FORCEPROP 1 LAST PACK_TYPE 2626
J 0
(-1350 1850);
DISPLAY 0.617021 (-1350 1850);
PAINT SKYBLUE (-1350 1850);
FORCEPROP 1 LAST VOLTAGE 16V
J 0
(-1350 1950);
DISPLAY 0.617021 (-1350 1950);
PAINT SKYBLUE (-1350 1950);
FORCEPROP 1 LAST MATERIAL OSCON
J 0
(-1350 1900);
DISPLAY 0.617021 (-1350 1900);
PAINT SKYBLUE (-1350 1900);
FORCEPROP 1 LASTPIN (-1400 2100) $PN 1
J 0
(-1390 2085);
DISPLAY 0.617021 (-1390 2085);
PAINT ORANGE (-1390 2085);
FORCEPROP 1 LAST VALUE 270UF
J 0
(-1350 2050);
DISPLAY 0.617021 (-1350 2050);
PAINT SKYBLUE (-1350 2050);
FORCEPROP 1 LAST LOCATION C4E16
J 0
(-1350 2100);
DISPLAY 0.617021 (-1350 2100);
PAINT AQUA (-1350 2100);
FORCEPROP 2 LAST ROOM PVCCIN_CPU0_FILTER_VR
J 0
(-1350 2150);
DISPLAY 1.361702 (-1350 2150);
PAINT ORANGE (-1350 2150);
DISPLAY INVISIBLE (-1350 2150);
FORCEPROP 1 LAST PATH I50
J 0
(-1350 2150);
DISPLAY 0.978723 (-1350 2150);
PAINT ORANGE (-1350 2150);
DISPLAY INVISIBLE (-1350 2150);
FORCEPROP 2 LAST CDS_LOCATION C4E16
J 0
(-1350 2100);
DISPLAY 0.617021 (-1350 2100);
PAINT AQUA (-1350 2100);
DISPLAY INVISIBLE (-1350 2100);
FORCEPROP 2 LAST SEC 1
J 0
(-1350 2200);
DISPLAY 0.680851 (-1350 2200);
PAINT MONO (-1350 2200);
DISPLAY INVISIBLE (-1350 2200);
FORCEPROP 2 LAST SEC_TYPE 2626
J 0
(-1350 2200);
DISPLAY 1.021277 (-1350 2200);
PAINT ORANGE (-1350 2200);
DISPLAY INVISIBLE (-1350 2200);
FORCEPROP 2 LAST CDS_LIB mstr_discrete
J 0
(-1400 2000);
PAINT ORANGE (-1400 2000);
DISPLAY INVISIBLE (-1400 2000);
FORCEADD CAP_A..1
(-2225 1050);
FORCEPROP 1 LAST TOLERANCE 10%
J 0
(-2175 1000);
DISPLAY 0.617021 (-2175 1000);
PAINT SKYBLUE (-2175 1000);
FORCEPROP 1 LAST LOCATION C4C2
J 0
(-2175 1150);
DISPLAY 0.617021 (-2175 1150);
PAINT AQUA (-2175 1150);
FORCEPROP 1 LAST VOLTAGE 16V
J 0
(-2175 1050);
DISPLAY 0.617021 (-2175 1050);
PAINT SKYBLUE (-2175 1050);
FORCEPROP 1 LAST MATERIAL EMPTY
J 0
(-2175 950);
DISPLAY 0.617021 (-2175 950);
PAINT RED (-2175 950);
FORCEPROP 1 LAST PART_NUMBER A36096-030
J 0
(-2175 900);
DISPLAY 0.617021 (-2175 900);
PAINT BLUE (-2175 900);
FORCEPROP 1 LAST VALUE 0.1UF
J 0
(-2175 1100);
DISPLAY 0.617021 (-2175 1100);
PAINT SKYBLUE (-2175 1100);
FORCEPROP 1 LAST PACK_TYPE 0402V
J 0
(-2175 850);
DISPLAY 0.617021 (-2175 850);
PAINT SKYBLUE (-2175 850);
FORCEPROP 2 LAST CDS_SEC 1
J 0
(-2175 1250);
PAINT MONO (-2175 1250);
DISPLAY INVISIBLE (-2175 1250);
FORCEPROP 2 LAST ROOM PVCCIN_CPU0_FILTER_VR
J 0
(-2175 1200);
DISPLAY 1.361702 (-2175 1200);
PAINT ORANGE (-2175 1200);
DISPLAY INVISIBLE (-2175 1200);
FORCEPROP 2 LAST CDS_LOCATION C4C2
J 0
(-2175 1150);
DISPLAY 0.617021 (-2175 1150);
PAINT AQUA (-2175 1150);
DISPLAY INVISIBLE (-2175 1150);
FORCEPROP 1 LAST PATH I51
J 0
(-2175 1200);
DISPLAY 0.978723 (-2175 1200);
PAINT WHITE (-2175 1200);
DISPLAY INVISIBLE (-2175 1200);
FORCEPROP 1 LASTPIN (-2225 1150) $PN 1
J 0
(-2215 1130);
DISPLAY 0.787234 (-2215 1130);
PAINT ORANGE (-2215 1130);
DISPLAY INVISIBLE (-2215 1130);
FORCEPROP 2 LAST CDS_LIB dev_discrete
J 0
(-2225 1050);
PAINT ORANGE (-2225 1050);
DISPLAY INVISIBLE (-2225 1050);
FORCEPROP 1 LASTPIN (-2225 950) $PN 2
J 0
(-2215 930);
DISPLAY 0.787234 (-2215 930);
PAINT ORANGE (-2215 930);
DISPLAY INVISIBLE (-2215 930);
FORCEADD GND..1
(-2225 800);
FORCEPROP 3 LASTPIN (-2225 850) SIG_NAME GND\g
J 0
(-2215 860);
DISPLAY 0.659574 (-2215 860);
PAINT MONO (-2215 860);
DISPLAY INVISIBLE (-2215 860);
FORCEPROP 1 LAST PATH I52
J 0
(-2150 800);
DISPLAY 0.872340 (-2150 800);
PAINT AQUA (-2150 800);
DISPLAY INVISIBLE (-2150 800);
FORCEPROP 1 LAST HDL_POWER GND
J 0
(-2225 950);
DISPLAY 0.893617 (-2225 950);
PAINT GREEN (-2225 950);
DISPLAY INVISIBLE (-2225 950);
FORCEPROP 1 LAST VOLTAGE 0
J 0
(-2225 800);
PAINT SKYBLUE (-2225 800);
DISPLAY INVISIBLE (-2225 800);
FORCEPROP 2 LAST CDS_LIB mstr_symbols
J 0
(-2225 800);
PAINT ORANGE (-2225 800);
DISPLAY INVISIBLE (-2225 800);
FORCEPROP 1 LAST SIZE 1B
J 0
(-2150 750);
DISPLAY 0.893617 (-2150 750);
PAINT GREEN (-2150 750);
DISPLAY INVISIBLE (-2150 750);
FORCEPROP 1 LAST BODY_TYPE PLUMBING
J 0
(-2270 757);
DISPLAY 0.340426 (-2270 757);
PAINT GREEN (-2270 757);
DISPLAY INVISIBLE (-2270 757);
FORCEPROP 2 LAST BOM_COST PROC_VRD_VCCIN_CPU0
J 0
(-2600 875);
PAINT MONO (-2600 875);
DISPLAY INVISIBLE (-2600 875);
FORCEPROP 2 LAST ROOM PVCCIN_CPU0_FILTER_VR
J 0
(-2775 875);
PAINT ORANGE (-2775 875);
DISPLAY INVISIBLE (-2775 875);
FORCEADD ADM4073..1
R 2
(-2750 1275);
FORCEPROP 2 LASTPIN (-3100 1175) $PN 2
J 2
(-3110 1185);
DISPLAY 0.617021 (-3110 1185);
PAINT ORANGE (-3110 1185);
FORCEPROP 2 LASTPIN (-3100 1125) $PN 1
J 2
(-3110 1135);
DISPLAY 0.617021 (-3110 1135);
PAINT ORANGE (-3110 1135);
FORCEPROP 2 LASTPIN (-3100 1375) $PN 6
J 2
(-3110 1385);
DISPLAY 0.617021 (-3110 1385);
PAINT ORANGE (-3110 1385);
FORCEPROP 1 LAST PART_NUMBER G12194-001
J 2
(-2450 975);
DISPLAY 0.617021 (-2450 975);
PAINT BLUE (-2450 975);
FORCEPROP 1 LAST MATERIAL EMPTY
J 2
(-2450 1575);
DISPLAY 0.617021 (-2450 1575);
PAINT RED (-2450 1575);
FORCEPROP 1 LAST LOCATION U4C1
J 2
(-2450 1625);
DISPLAY 0.617021 (-2450 1625);
PAINT AQUA (-2450 1625);
FORCEPROP 2 LASTPIN (-2400 1225) $PN 5
J 0
(-2390 1235);
DISPLAY 0.617021 (-2390 1235);
PAINT ORANGE (-2390 1235);
FORCEPROP 2 LASTPIN (-2400 1375) $PN 3
J 0
(-2390 1385);
DISPLAY 0.617021 (-2390 1385);
PAINT ORANGE (-2390 1385);
FORCEPROP 2 LASTPIN (-2400 1275) $PN 4
J 0
(-2390 1285);
DISPLAY 0.617021 (-2390 1285);
PAINT ORANGE (-2390 1285);
FORCEPROP 1 LAST PACK_TYPE SM
J 2
(-2450 1675);
DISPLAY 1.340426 (-2450 1675);
PAINT SKYBLUE (-2450 1675);
DISPLAY INVISIBLE (-2450 1675);
FORCEPROP 2 LAST SEC_TYPE SM
J 0
(-2450 1675);
DISPLAY 1.361702 (-2450 1675);
PAINT ORANGE (-2450 1675);
DISPLAY INVISIBLE (-2450 1675);
FORCEPROP 2 LAST SEC 1
J 0
(-2450 1675);
DISPLAY 0.914894 (-2450 1675);
PAINT MONO (-2450 1675);
DISPLAY INVISIBLE (-2450 1675);
FORCEPROP 2 LAST CDS_LOCATION U4C1
J 2
(-2450 1625);
DISPLAY 0.617021 (-2450 1625);
PAINT AQUA (-2450 1625);
DISPLAY INVISIBLE (-2450 1625);
FORCEPROP 2 LAST ROOM PVCCIN_CPU0_FILTER_VR
J 0
(-2450 1675);
DISPLAY 1.361702 (-2450 1675);
PAINT ORANGE (-2450 1675);
DISPLAY INVISIBLE (-2450 1675);
FORCEPROP 1 LAST PATH I53
J 2
(-2750 1575);
PAINT GREEN (-2750 1575);
DISPLAY INVISIBLE (-2750 1575);
FORCEPROP 2 LAST CDS_LIB mstr_analog
J 2
(-2750 1275);
PAINT ORANGE (-2750 1275);
DISPLAY INVISIBLE (-2750 1275);
FORCEADD GND..1
(-3275 950);
FORCEPROP 3 LASTPIN (-3275 1000) SIG_NAME GND\g
J 0
(-3265 1010);
DISPLAY 0.659574 (-3265 1010);
PAINT MONO (-3265 1010);
DISPLAY INVISIBLE (-3265 1010);
FORCEPROP 1 LAST HDL_POWER GND
J 0
(-3275 1100);
DISPLAY 0.893617 (-3275 1100);
PAINT GREEN (-3275 1100);
DISPLAY INVISIBLE (-3275 1100);
FORCEPROP 2 LAST BOM_COST PROC_VRD_VCCIN_CPU0
J 0
(-3650 1025);
PAINT MONO (-3650 1025);
DISPLAY INVISIBLE (-3650 1025);
FORCEPROP 2 LAST ROOM PVCCIN_CPU0_FILTER_VR
J 0
(-3825 1025);
PAINT ORANGE (-3825 1025);
DISPLAY INVISIBLE (-3825 1025);
FORCEPROP 1 LAST VOLTAGE 0
J 0
(-3275 950);
PAINT SKYBLUE (-3275 950);
DISPLAY INVISIBLE (-3275 950);
FORCEPROP 1 LAST SIZE 1B
J 0
(-3200 900);
DISPLAY 0.893617 (-3200 900);
PAINT GREEN (-3200 900);
DISPLAY INVISIBLE (-3200 900);
FORCEPROP 2 LAST CDS_LIB mstr_symbols
J 0
(-3275 950);
PAINT ORANGE (-3275 950);
DISPLAY INVISIBLE (-3275 950);
FORCEPROP 1 LAST BODY_TYPE PLUMBING
J 0
(-3320 907);
DISPLAY 0.340426 (-3320 907);
PAINT GREEN (-3320 907);
DISPLAY INVISIBLE (-3320 907);
FORCEPROP 1 LAST PATH I54
J 0
(-3200 950);
DISPLAY 0.872340 (-3200 950);
PAINT AQUA (-3200 950);
DISPLAY INVISIBLE (-3200 950);
FORCEADD OFFPAGE..2
R 2
(-3825 1600);
FORCEPROP 2 LAST $XR0 201 
J 0
(-4080 1600);
DISPLAY 0.638298 (-4080 1600);
PAINT MONO (-4080 1600);
FORCEPROP 2 LAST ROOM PVCCIN_CPU0_FILTER_VR
J 2
(-3425 1675);
PAINT ORANGE (-3425 1675);
DISPLAY INVISIBLE (-3425 1675);
FORCEPROP 2 LAST CDS_LIB mstr_standard
J 2
(-3825 1600);
PAINT ORANGE (-3825 1600);
DISPLAY INVISIBLE (-3825 1600);
FORCEPROP 2 LAST PATH I55
J 0
(-3760 1660);
DISPLAY 1.021277 (-3760 1660);
PAINT ORANGE (-3760 1660);
DISPLAY INVISIBLE (-3760 1660);
FORCEPROP 2 LAST BOM_COST PROC_VRD_VCCIN_CPU0
J 2
(-4025 1650);
PAINT MONO (-4025 1650);
DISPLAY INVISIBLE (-4025 1650);
FORCEPROP 1 LAST COMMENT_BODY TRUE
J 2
(-3780 1505);
DISPLAY 0.893617 (-3780 1505);
PAINT GREEN (-3780 1505);
DISPLAY INVISIBLE (-3780 1505);
FORCEPROP 1 LAST OFFPAGE TRUE
J 2
(-4150 1475);
DISPLAY 0.893617 (-4150 1475);
PAINT GREEN (-4150 1475);
DISPLAY INVISIBLE (-4150 1475);
FORCEADD OFFPAGE..2
(-4275 1825);
FORCEPROP 2 LAST $XR0 37 
J 0
(-4086 1825);
DISPLAY 0.638298 (-4086 1825);
PAINT MONO (-4086 1825);
FORCEPROP 2 LAST BOM_COST PROC_VRD_VCCIN_CPU0
J 0
(-3950 1875);
PAINT MONO (-3950 1875);
DISPLAY INVISIBLE (-3950 1875);
FORCEPROP 1 LAST OFFPAGE TRUE
J 0
(-3950 1700);
DISPLAY 0.893617 (-3950 1700);
PAINT GREEN (-3950 1700);
DISPLAY INVISIBLE (-3950 1700);
FORCEPROP 2 LAST PATH I56
J 0
(-3960 1885);
DISPLAY 1.021277 (-3960 1885);
PAINT ORANGE (-3960 1885);
DISPLAY INVISIBLE (-3960 1885);
FORCEPROP 2 LAST CDS_LIB mstr_standard
J 2
(-4275 1825);
PAINT ORANGE (-4275 1825);
DISPLAY INVISIBLE (-4275 1825);
FORCEPROP 1 LAST COMMENT_BODY TRUE
J 0
(-4320 1730);
DISPLAY 0.893617 (-4320 1730);
PAINT GREEN (-4320 1730);
DISPLAY INVISIBLE (-4320 1730);
FORCEPROP 2 LAST ROOM PVCCIN_CPU0_VSENSE_VR
J 0
(-4675 1900);
PAINT ORANGE (-4675 1900);
DISPLAY INVISIBLE (-4675 1900);
FORCEADD OFFPAGE..2
(-4275 1375);
FORCEPROP 2 LAST $XR0 37 
J 0
(-4086 1375);
DISPLAY 0.638298 (-4086 1375);
PAINT MONO (-4086 1375);
FORCEPROP 2 LAST BOM_COST PROC_VRD_VCCIN_CPU0
J 0
(-4075 1425);
PAINT MONO (-4075 1425);
DISPLAY INVISIBLE (-4075 1425);
FORCEPROP 1 LAST OFFPAGE TRUE
J 0
(-3950 1250);
DISPLAY 0.893617 (-3950 1250);
PAINT GREEN (-3950 1250);
DISPLAY INVISIBLE (-3950 1250);
FORCEPROP 2 LAST PATH I57
J 0
(-4085 1435);
DISPLAY 1.021277 (-4085 1435);
PAINT ORANGE (-4085 1435);
DISPLAY INVISIBLE (-4085 1435);
FORCEPROP 2 LAST CDS_LIB mstr_standard
J 0
(-4275 1375);
PAINT ORANGE (-4275 1375);
DISPLAY INVISIBLE (-4275 1375);
FORCEPROP 1 LAST COMMENT_BODY TRUE
J 0
(-4320 1280);
DISPLAY 0.893617 (-4320 1280);
PAINT GREEN (-4320 1280);
DISPLAY INVISIBLE (-4320 1280);
FORCEPROP 2 LAST ROOM PVCCIN_CPU0_VSENSE_VR
J 0
(-4675 1450);
PAINT ORANGE (-4675 1450);
DISPLAY INVISIBLE (-4675 1450);
FORCEADD PVCCIN_CPU0..1
(-4625 2375);
FORCEPROP 3 LASTPIN (-4625 2325) SIG_NAME PVCCIN_CPU0\g
J 0
(-4615 2335);
DISPLAY 0.659574 (-4615 2335);
PAINT MONO (-4615 2335);
DISPLAY INVISIBLE (-4615 2335);
FORCEPROP 1 LAST PATH I58
J 0
(-4575 2400);
DISPLAY 0.872340 (-4575 2400);
PAINT AQUA (-4575 2400);
DISPLAY INVISIBLE (-4575 2400);
FORCEPROP 1 LAST BODY_TYPE PLUMBING
J 0
(-4670 2332);
DISPLAY 0.340426 (-4670 2332);
PAINT GREEN (-4670 2332);
DISPLAY INVISIBLE (-4670 2332);
FORCEPROP 2 LAST CDS_LIB mstr_symbols
J 0
(-4625 2375);
PAINT ORANGE (-4625 2375);
DISPLAY INVISIBLE (-4625 2375);
FORCEPROP 1 LAST VOLTAGE 2.0V
J 0
(-4670 2332);
DISPLAY 0.340426 (-4670 2332);
PAINT SKYBLUE (-4670 2332);
DISPLAY INVISIBLE (-4670 2332);
FORCEPROP 1 LAST HDL_POWER PVCCIN_CPU0
J 1
(-4625 2425);
DISPLAY 0.872340 (-4625 2425);
PAINT GREEN (-4625 2425);
DISPLAY INVISIBLE (-4625 2425);
FORCEADD GND..1
(-4800 700);
FORCEPROP 3 LASTPIN (-4800 750) SIG_NAME GND\g
J 0
(-4790 760);
DISPLAY 0.659574 (-4790 760);
PAINT MONO (-4790 760);
DISPLAY INVISIBLE (-4790 760);
FORCEPROP 1 LAST HDL_POWER GND
J 0
(-4800 850);
DISPLAY 0.893617 (-4800 850);
PAINT GREEN (-4800 850);
DISPLAY INVISIBLE (-4800 850);
FORCEPROP 1 LAST VOLTAGE 0
J 0
(-4800 700);
PAINT SKYBLUE (-4800 700);
DISPLAY INVISIBLE (-4800 700);
FORCEPROP 1 LAST SIZE 1B
J 0
(-4725 650);
DISPLAY 0.893617 (-4725 650);
PAINT GREEN (-4725 650);
DISPLAY INVISIBLE (-4725 650);
FORCEPROP 2 LAST CDS_LIB mstr_symbols
J 0
(-4800 700);
PAINT ORANGE (-4800 700);
DISPLAY INVISIBLE (-4800 700);
FORCEPROP 1 LAST BODY_TYPE PLUMBING
J 0
(-4845 657);
DISPLAY 0.340426 (-4845 657);
PAINT GREEN (-4845 657);
DISPLAY INVISIBLE (-4845 657);
FORCEPROP 1 LAST PATH I59
J 0
(-4725 700);
DISPLAY 0.872340 (-4725 700);
PAINT AQUA (-4725 700);
DISPLAY INVISIBLE (-4725 700);
FORCEPROP 2 LAST BOM_COST PROC_VRD_VCCIN_CPU0
J 0
(-5175 775);
PAINT MONO (-5175 775);
DISPLAY INVISIBLE (-5175 775);
FORCEPROP 2 LAST ROOM PVCCIN_CPU0_VSENSE_VR
J 0
(-5350 775);
PAINT ORANGE (-5350 775);
DISPLAY INVISIBLE (-5350 775);
FORCEADD RES..1
(-5475 2225);
FORCEPROP 1 LASTPIN (-5575 2225) $PN 1
J 0
(-5563 2237);
DISPLAY 0.617021 (-5563 2237);
PAINT GREEN (-5563 2237);
FORCEPROP 1 LAST PACK_TYPE 0402
J 0
(-5550 2050);
DISPLAY 0.617021 (-5550 2050);
PAINT SKYBLUE (-5550 2050);
FORCEPROP 1 LAST LOCATION R4E14
J 0
(-5525 2275);
DISPLAY 0.617021 (-5525 2275);
PAINT AQUA (-5525 2275);
FORCEPROP 1 LAST VALUE 100.0
J 2
(-5475 2150);
DISPLAY 0.617021 (-5475 2150);
PAINT SKYBLUE (-5475 2150);
FORCEPROP 1 LAST WATTAGE 1/16W
J 2
(-5475 2100);
DISPLAY 0.617021 (-5475 2100);
PAINT SKYBLUE (-5475 2100);
FORCEPROP 1 LASTPIN (-5375 2225) $PN 2
J 0
(-5413 2237);
DISPLAY 0.617021 (-5413 2237);
PAINT GREEN (-5413 2237);
FORCEPROP 1 LAST TOLERANCE 1%
J 0
(-5425 2150);
DISPLAY 0.617021 (-5425 2150);
PAINT SKYBLUE (-5425 2150);
FORCEPROP 1 LAST PART_NUMBER G21796-017
J 0
(-5525 2325);
DISPLAY 0.617021 (-5525 2325);
PAINT BLUE (-5525 2325);
FORCEPROP 2 LAST CDS_SEC 1
J 0
(-5525 2425);
PAINT MONO (-5525 2425);
DISPLAY INVISIBLE (-5525 2425);
FORCEPROP 2 LAST $SEC 1
J 0
(-5525 2425);
PAINT MONO (-5525 2425);
DISPLAY INVISIBLE (-5525 2425);
FORCEPROP 1 LAST PATH I60
J 0
(-5525 2375);
DISPLAY 0.978723 (-5525 2375);
PAINT WHITE (-5525 2375);
DISPLAY INVISIBLE (-5525 2375);
FORCEPROP 2 LAST ROOM PVCCIN_CPU0_VSENSE_VR
J 0
(-5525 2325);
PAINT ORANGE (-5525 2325);
DISPLAY INVISIBLE (-5525 2325);
FORCEPROP 2 LAST BOM_COST PROC_VRD_VCCIN_CPU0
J 0
(-5525 2375);
PAINT MONO (-5525 2375);
DISPLAY INVISIBLE (-5525 2375);
FORCEPROP 1 LAST MATERIAL CHIP
J 0
(-5450 2100);
PAINT SKYBLUE (-5450 2100);
DISPLAY INVISIBLE (-5450 2100);
FORCEPROP 2 LAST CDS_LIB mstr_discrete
J 0
(-5475 2225);
PAINT ORANGE (-5475 2225);
DISPLAY INVISIBLE (-5475 2225);
FORCEPROP 2 LAST CDS_LOCATION R4E14
J 0
(-5525 2275);
DISPLAY 0.617021 (-5525 2275);
PAINT AQUA (-5525 2275);
DISPLAY INVISIBLE (-5525 2275);
FORCEADD RES..1
(-5475 1825);
FORCEPROP 1 LAST WATTAGE 1/16W
J 2
(-5500 1675);
DISPLAY 0.617021 (-5500 1675);
PAINT SKYBLUE (-5500 1675);
FORCEPROP 1 LAST TOLERANCE 5%
J 0
(-5475 1750);
DISPLAY 0.617021 (-5475 1750);
PAINT SKYBLUE (-5475 1750);
FORCEPROP 1 LAST VALUE 0.0
J 2
(-5500 1750);
DISPLAY 0.617021 (-5500 1750);
PAINT SKYBLUE (-5500 1750);
FORCEPROP 1 LAST PACK_TYPE 0402
J 0
(-5600 1625);
DISPLAY 0.617021 (-5600 1625);
PAINT SKYBLUE (-5600 1625);
FORCEPROP 1 LASTPIN (-5575 1825) $PN 1
J 0
(-5563 1837);
DISPLAY 0.617021 (-5563 1837);
PAINT GREEN (-5563 1837);
FORCEPROP 1 LAST LOCATION R4E16
J 0
(-5525 1875);
DISPLAY 0.617021 (-5525 1875);
PAINT AQUA (-5525 1875);
FORCEPROP 1 LASTPIN (-5375 1825) $PN 2
J 0
(-5413 1837);
DISPLAY 0.617021 (-5413 1837);
PAINT GREEN (-5413 1837);
FORCEPROP 1 LAST PART_NUMBER G21497-005
J 0
(-5600 1925);
DISPLAY 0.617021 (-5600 1925);
PAINT BLUE (-5600 1925);
FORCEPROP 1 LAST MATERIAL CHIP
J 0
(-5475 1675);
DISPLAY 0.617021 (-5475 1675);
PAINT SKYBLUE (-5475 1675);
FORCEPROP 2 LAST NO_XNET_CONNECTION 1
J 0
(-5525 2025);
PAINT MONO (-5525 2025);
FORCEPROP 2 LAST CDS_SEC 1
J 0
(-5525 2025);
PAINT MONO (-5525 2025);
DISPLAY INVISIBLE (-5525 2025);
FORCEPROP 2 LAST $SEC 1
J 0
(-5525 2025);
PAINT MONO (-5525 2025);
DISPLAY INVISIBLE (-5525 2025);
FORCEPROP 2 LAST CDS_LIB mstr_discrete
J 0
(-5475 1825);
PAINT ORANGE (-5475 1825);
DISPLAY INVISIBLE (-5475 1825);
FORCEPROP 2 LAST BOM_COST PROC_VRD_VCCIN_CPU0
J 0
(-5600 1975);
PAINT MONO (-5600 1975);
DISPLAY INVISIBLE (-5600 1975);
FORCEPROP 2 LAST CDS_LOCATION R4E16
J 0
(-5525 1875);
DISPLAY 0.617021 (-5525 1875);
PAINT AQUA (-5525 1875);
DISPLAY INVISIBLE (-5525 1875);
FORCEPROP 1 LAST PATH I61
J 0
(-5525 1975);
DISPLAY 0.978723 (-5525 1975);
PAINT WHITE (-5525 1975);
DISPLAY INVISIBLE (-5525 1975);
FORCEPROP 2 LAST ROOM PVCCIN_CPU0_VSENSE_VR
J 0
(-5525 1925);
PAINT ORANGE (-5525 1925);
DISPLAY INVISIBLE (-5525 1925);
FORCEADD RES..1
(-5450 1375);
FORCEPROP 1 LAST PACK_TYPE 0402
J 0
(-5575 1175);
DISPLAY 0.617021 (-5575 1175);
PAINT SKYBLUE (-5575 1175);
FORCEPROP 1 LAST WATTAGE 1/16W
J 2
(-5475 1225);
DISPLAY 0.617021 (-5475 1225);
PAINT SKYBLUE (-5475 1225);
FORCEPROP 1 LASTPIN (-5550 1375) $PN 1
J 0
(-5538 1387);
DISPLAY 0.617021 (-5538 1387);
PAINT GREEN (-5538 1387);
FORCEPROP 1 LAST VALUE 0.0
J 2
(-5475 1300);
DISPLAY 0.617021 (-5475 1300);
PAINT SKYBLUE (-5475 1300);
FORCEPROP 1 LAST TOLERANCE 5%
J 0
(-5450 1300);
DISPLAY 0.617021 (-5450 1300);
PAINT SKYBLUE (-5450 1300);
FORCEPROP 1 LAST LOCATION R4E17
J 0
(-5500 1425);
DISPLAY 0.617021 (-5500 1425);
PAINT AQUA (-5500 1425);
FORCEPROP 1 LAST PART_NUMBER G21497-005
J 0
(-5575 1475);
DISPLAY 0.617021 (-5575 1475);
PAINT BLUE (-5575 1475);
FORCEPROP 1 LAST MATERIAL CHIP
J 0
(-5450 1225);
DISPLAY 0.617021 (-5450 1225);
PAINT SKYBLUE (-5450 1225);
FORCEPROP 1 LASTPIN (-5350 1375) $PN 2
J 0
(-5388 1387);
DISPLAY 0.617021 (-5388 1387);
PAINT GREEN (-5388 1387);
FORCEPROP 2 LAST NO_XNET_CONNECTION 1
J 0
(-5500 1575);
PAINT MONO (-5500 1575);
FORCEPROP 2 LAST CDS_SEC 1
J 0
(-5500 1575);
PAINT MONO (-5500 1575);
DISPLAY INVISIBLE (-5500 1575);
FORCEPROP 2 LAST $SEC 1
J 0
(-5500 1575);
PAINT MONO (-5500 1575);
DISPLAY INVISIBLE (-5500 1575);
FORCEPROP 2 LAST BOM_COST PROC_VRD_VCCIN_CPU0
J 0
(-5575 1525);
PAINT MONO (-5575 1525);
DISPLAY INVISIBLE (-5575 1525);
FORCEPROP 1 LAST PATH I62
J 0
(-5500 1525);
DISPLAY 0.978723 (-5500 1525);
PAINT WHITE (-5500 1525);
DISPLAY INVISIBLE (-5500 1525);
FORCEPROP 2 LAST ROOM PVCCIN_CPU0_VSENSE_VR
J 0
(-5500 1475);
PAINT ORANGE (-5500 1475);
DISPLAY INVISIBLE (-5500 1475);
FORCEPROP 2 LAST CDS_LOCATION R4E17
J 0
(-5500 1425);
DISPLAY 0.617021 (-5500 1425);
PAINT AQUA (-5500 1425);
DISPLAY INVISIBLE (-5500 1425);
FORCEPROP 2 LAST CDS_LIB mstr_discrete
J 0
(-5450 1375);
PAINT ORANGE (-5450 1375);
DISPLAY INVISIBLE (-5450 1375);
FORCEADD RES..2
(-6275 1625);
FORCEPROP 1 LASTPIN (-6275 1525) $PN 2
J 0
(-6270 1535);
DISPLAY 0.617021 (-6270 1535);
PAINT GREEN (-6270 1535);
FORCEPROP 1 LAST TOLERANCE 1%
J 0
(-6230 1650);
DISPLAY 0.617021 (-6230 1650);
PAINT SKYBLUE (-6230 1650);
FORCEPROP 1 LASTPIN (-6275 1725) $PN 1
J 0
(-6270 1687);
DISPLAY 0.617021 (-6270 1687);
PAINT GREEN (-6270 1687);
FORCEPROP 2 LAST NO_XNET_CONNECTION 1
J 0
(-6225 1850);
PAINT MONO (-6225 1850);
FORCEPROP 1 LAST MATERIAL EMPTY
J 0
(-6235 1550);
DISPLAY 0.617021 (-6235 1550);
PAINT RED (-6235 1550);
FORCEPROP 1 LAST LOCATION R4E15
J 0
(-6230 1750);
DISPLAY 0.617021 (-6230 1750);
PAINT AQUA (-6230 1750);
FORCEPROP 1 LAST PART_NUMBER G21796-026
J 0
(-6235 1500);
DISPLAY 0.617021 (-6235 1500);
PAINT BLUE (-6235 1500);
FORCEPROP 1 LAST VALUE 1.00K
J 0
(-6230 1700);
DISPLAY 0.617021 (-6230 1700);
PAINT SKYBLUE (-6230 1700);
FORCEPROP 1 LAST PACK_TYPE 0402
J 0
(-6235 1450);
DISPLAY 0.617021 (-6235 1450);
PAINT SKYBLUE (-6235 1450);
FORCEPROP 1 LAST WATTAGE 1/16W
J 0
(-6235 1600);
DISPLAY 0.617021 (-6235 1600);
PAINT SKYBLUE (-6235 1600);
FORCEPROP 2 LAST BOM_COST PROC_VRD_VCCIN_CPU0
J 0
(-6225 1800);
PAINT MONO (-6225 1800);
DISPLAY INVISIBLE (-6225 1800);
FORCEPROP 2 LAST CDS_SEC 1
J 0
(-6225 1850);
PAINT MONO (-6225 1850);
DISPLAY INVISIBLE (-6225 1850);
FORCEPROP 2 LAST $SEC 1
J 0
(-6225 1850);
PAINT MONO (-6225 1850);
DISPLAY INVISIBLE (-6225 1850);
FORCEPROP 1 LAST PATH I63
J 0
(-6225 1800);
DISPLAY 0.978723 (-6225 1800);
PAINT WHITE (-6225 1800);
DISPLAY INVISIBLE (-6225 1800);
FORCEPROP 2 LAST ROOM PVCCIN_CPU0_VSENSE_VR
J 0
(-6225 1800);
PAINT MONO (-6225 1800);
DISPLAY INVISIBLE (-6225 1800);
FORCEPROP 2 LAST CDS_LOCATION R4E15
J 0
(-6230 1750);
DISPLAY 0.617021 (-6230 1750);
PAINT AQUA (-6230 1750);
DISPLAY INVISIBLE (-6230 1750);
FORCEPROP 2 LAST CDS_LIB mstr_discrete
J 0
(-6275 1625);
PAINT ORANGE (-6275 1625);
DISPLAY INVISIBLE (-6275 1625);
FORCEADD RES..1
(-5450 975);
FORCEPROP 1 LASTPIN (-5550 975) $PN 1
J 0
(-5538 987);
DISPLAY 0.617021 (-5538 987);
PAINT GREEN (-5538 987);
FORCEPROP 1 LAST WATTAGE 1/16W
J 2
(-5450 850);
DISPLAY 0.617021 (-5450 850);
PAINT SKYBLUE (-5450 850);
FORCEPROP 1 LAST VALUE 100.0
J 2
(-5450 900);
DISPLAY 0.617021 (-5450 900);
PAINT SKYBLUE (-5450 900);
FORCEPROP 1 LAST PACK_TYPE 0402
J 0
(-5525 800);
DISPLAY 0.617021 (-5525 800);
PAINT SKYBLUE (-5525 800);
FORCEPROP 1 LASTPIN (-5350 975) $PN 2
J 0
(-5388 987);
DISPLAY 0.617021 (-5388 987);
PAINT GREEN (-5388 987);
FORCEPROP 1 LAST TOLERANCE 1%
J 0
(-5400 900);
DISPLAY 0.617021 (-5400 900);
PAINT SKYBLUE (-5400 900);
FORCEPROP 1 LAST LOCATION R4E18
J 0
(-5500 1025);
DISPLAY 0.617021 (-5500 1025);
PAINT AQUA (-5500 1025);
FORCEPROP 1 LAST PART_NUMBER G21796-017
J 0
(-5500 1075);
DISPLAY 0.617021 (-5500 1075);
PAINT BLUE (-5500 1075);
FORCEPROP 2 LAST CDS_SEC 1
J 0
(-5500 1175);
PAINT MONO (-5500 1175);
DISPLAY INVISIBLE (-5500 1175);
FORCEPROP 2 LAST $SEC 1
J 0
(-5500 1175);
PAINT MONO (-5500 1175);
DISPLAY INVISIBLE (-5500 1175);
FORCEPROP 2 LAST CDS_LOCATION R4E18
J 0
(-5500 1025);
DISPLAY 0.617021 (-5500 1025);
PAINT AQUA (-5500 1025);
DISPLAY INVISIBLE (-5500 1025);
FORCEPROP 1 LAST PATH I64
J 0
(-5500 1125);
DISPLAY 0.978723 (-5500 1125);
PAINT WHITE (-5500 1125);
DISPLAY INVISIBLE (-5500 1125);
FORCEPROP 2 LAST ROOM PVCCIN_CPU0_VSENSE_VR
J 0
(-5500 1075);
PAINT ORANGE (-5500 1075);
DISPLAY INVISIBLE (-5500 1075);
FORCEPROP 2 LAST BOM_COST PROC_VRD_VCCIN_CPU0
J 0
(-5500 1125);
PAINT MONO (-5500 1125);
DISPLAY INVISIBLE (-5500 1125);
FORCEPROP 2 LAST CDS_LIB mstr_discrete
J 0
(-5450 975);
PAINT ORANGE (-5450 975);
DISPLAY INVISIBLE (-5450 975);
FORCEPROP 1 LAST MATERIAL CHIP
J 0
(-5425 850);
PAINT SKYBLUE (-5425 850);
DISPLAY INVISIBLE (-5425 850);
FORCEADD OFFPAGE..1
(-7600 1775);
FORCEPROP 2 LAST $XR0 201 
J 0
(-7852 1775);
DISPLAY 0.638298 (-7852 1775);
PAINT MONO (-7852 1775);
FORCEPROP 2 LAST CDS_LIB mstr_standard
J 2
(-7600 1775);
PAINT ORANGE (-7600 1775);
DISPLAY INVISIBLE (-7600 1775);
FORCEPROP 1 LAST OFFPAGE TRUE
J 0
(-7275 1650);
DISPLAY 0.893617 (-7275 1650);
PAINT GREEN (-7275 1650);
DISPLAY INVISIBLE (-7275 1650);
FORCEPROP 1 LAST COMMENT_BODY TRUE
J 0
(-7475 1675);
DISPLAY 0.893617 (-7475 1675);
PAINT GREEN (-7475 1675);
DISPLAY INVISIBLE (-7475 1675);
FORCEPROP 2 LAST PATH I65
J 0
(-7810 1835);
DISPLAY 1.021277 (-7810 1835);
PAINT ORANGE (-7810 1835);
DISPLAY INVISIBLE (-7810 1835);
FORCEPROP 2 LAST BOM_COST PROC_VRD_VCCIN_CPU0
J 0
(-7800 1825);
PAINT MONO (-7800 1825);
DISPLAY INVISIBLE (-7800 1825);
FORCEPROP 2 LAST ROOM PVCCIN_CPU0_VSENSE_VR
J 0
(-8125 1850);
PAINT ORANGE (-8125 1850);
DISPLAY INVISIBLE (-8125 1850);
FORCEADD OFFPAGE..1
(-7600 1500);
FORCEPROP 2 LAST $XR0 201 
J 0
(-7852 1500);
DISPLAY 0.638298 (-7852 1500);
PAINT MONO (-7852 1500);
FORCEPROP 2 LAST CDS_LIB mstr_standard
J 0
(-7600 1500);
PAINT ORANGE (-7600 1500);
DISPLAY INVISIBLE (-7600 1500);
FORCEPROP 1 LAST OFFPAGE TRUE
J 0
(-7275 1375);
DISPLAY 0.893617 (-7275 1375);
PAINT GREEN (-7275 1375);
DISPLAY INVISIBLE (-7275 1375);
FORCEPROP 1 LAST COMMENT_BODY TRUE
J 0
(-7475 1400);
DISPLAY 0.893617 (-7475 1400);
PAINT GREEN (-7475 1400);
DISPLAY INVISIBLE (-7475 1400);
FORCEPROP 2 LAST PATH I66
J 0
(-7810 1560);
DISPLAY 1.021277 (-7810 1560);
PAINT ORANGE (-7810 1560);
DISPLAY INVISIBLE (-7810 1560);
FORCEPROP 2 LAST BOM_COST PROC_VRD_VCCIN_CPU0
J 0
(-7800 1550);
PAINT MONO (-7800 1550);
DISPLAY INVISIBLE (-7800 1550);
FORCEPROP 2 LAST ROOM PVCCIN_CPU0_VSENSE_VR
J 0
(-8125 1575);
PAINT ORANGE (-8125 1575);
DISPLAY INVISIBLE (-8125 1575);
FORCEADD CAPP..1
(-575 1975);
FORCEPROP 1 LASTPIN (-575 1875) $PN 2
J 0
(-565 1860);
DISPLAY 0.617021 (-565 1860);
PAINT ORANGE (-565 1860);
FORCEPROP 1 LAST PART_NUMBER A31228-047
J 0
(-525 1775);
DISPLAY 0.617021 (-525 1775);
PAINT BLUE (-525 1775);
FORCEPROP 1 LAST TOLERANCE 20%
J 0
(-525 1975);
DISPLAY 0.617021 (-525 1975);
PAINT SKYBLUE (-525 1975);
FORCEPROP 1 LAST PACK_TYPE 2626
J 0
(-525 1825);
DISPLAY 0.617021 (-525 1825);
PAINT SKYBLUE (-525 1825);
FORCEPROP 1 LAST VOLTAGE 16V
J 0
(-525 1925);
DISPLAY 0.617021 (-525 1925);
PAINT SKYBLUE (-525 1925);
FORCEPROP 1 LAST MATERIAL OSCON
J 0
(-525 1875);
DISPLAY 0.617021 (-525 1875);
PAINT SKYBLUE (-525 1875);
FORCEPROP 1 LAST VALUE 270UF
J 0
(-525 2025);
DISPLAY 0.617021 (-525 2025);
PAINT SKYBLUE (-525 2025);
FORCEPROP 1 LASTPIN (-575 2075) $PN 1
J 0
(-565 2060);
DISPLAY 0.617021 (-565 2060);
PAINT ORANGE (-565 2060);
FORCEPROP 1 LAST LOCATION C4C12
J 0
(-525 2075);
DISPLAY 0.617021 (-525 2075);
PAINT AQUA (-525 2075);
FORCEPROP 2 LAST SEC_TYPE 2626
J 0
(-525 2175);
DISPLAY 1.021277 (-525 2175);
PAINT ORANGE (-525 2175);
DISPLAY INVISIBLE (-525 2175);
FORCEPROP 2 LAST SEC 1
J 0
(-525 2175);
DISPLAY 0.680851 (-525 2175);
PAINT MONO (-525 2175);
DISPLAY INVISIBLE (-525 2175);
FORCEPROP 2 LAST ROOM PVCCIN_CPU0_FILTER_VR
J 0
(-525 2125);
DISPLAY 1.361702 (-525 2125);
PAINT ORANGE (-525 2125);
DISPLAY INVISIBLE (-525 2125);
FORCEPROP 2 LAST CDS_LOCATION C4C12
J 0
(-525 2075);
DISPLAY 0.617021 (-525 2075);
PAINT AQUA (-525 2075);
DISPLAY INVISIBLE (-525 2075);
FORCEPROP 1 LAST PATH I67
J 0
(-525 2125);
DISPLAY 0.978723 (-525 2125);
PAINT ORANGE (-525 2125);
DISPLAY INVISIBLE (-525 2125);
FORCEPROP 2 LAST CDS_LIB mstr_discrete
J 0
(-575 1975);
PAINT ORANGE (-575 1975);
DISPLAY INVISIBLE (-575 1975);
FORCEADD P12V_STBY..1
(-3325 2425);
FORCEPROP 3 LASTPIN (-3325 2375) SIG_NAME P12V_STBY\g
J 0
(-3315 2385);
DISPLAY 0.659574 (-3315 2385);
PAINT MONO (-3315 2385);
DISPLAY INVISIBLE (-3315 2385);
FORCEPROP 2 LAST CDS_LIB mstr_symbols
J 0
(-3325 2425);
PAINT ORANGE (-3325 2425);
DISPLAY INVISIBLE (-3325 2425);
FORCEPROP 1 LAST SIZE 1B
J 0
(-3280 2447);
DISPLAY 0.340426 (-3280 2447);
PAINT GREEN (-3280 2447);
DISPLAY INVISIBLE (-3280 2447);
FORCEPROP 1 LAST PATH I68
J 0
(-3280 2427);
DISPLAY 0.340426 (-3280 2427);
PAINT GREEN (-3280 2427);
DISPLAY INVISIBLE (-3280 2427);
FORCEPROP 1 LAST BODY_TYPE PLUMBING
J 0
(-3370 2382);
DISPLAY 0.340426 (-3370 2382);
PAINT GREEN (-3370 2382);
DISPLAY INVISIBLE (-3370 2382);
FORCEPROP 1 LAST VOLTAGE 12.0V
J 0
(-3370 2382);
DISPLAY 0.340426 (-3370 2382);
PAINT SKYBLUE (-3370 2382);
DISPLAY INVISIBLE (-3370 2382);
FORCEPROP 1 LAST HDL_POWER P12V_STBY
J 0
(-3625 2300);
DISPLAY 0.872340 (-3625 2300);
PAINT ORANGE (-3625 2300);
DISPLAY INVISIBLE (-3625 2300);
FORCEADD P5V_STBY..1
(-5325 4650);
FORCEPROP 3 LASTPIN (-5325 4600) SIG_NAME P5V_STBY\g
J 0
(-5315 4610);
DISPLAY 0.659574 (-5315 4610);
PAINT MONO (-5315 4610);
DISPLAY INVISIBLE (-5315 4610);
FORCEPROP 1 LAST PATH I69
J 0
(-5280 4652);
DISPLAY 0.340426 (-5280 4652);
PAINT GREEN (-5280 4652);
DISPLAY INVISIBLE (-5280 4652);
FORCEPROP 2 LAST CDS_LIB mstr_symbols
J 0
(-5325 4650);
PAINT ORANGE (-5325 4650);
DISPLAY INVISIBLE (-5325 4650);
FORCEPROP 1 LAST SIZE 1B
J 0
(-5280 4672);
DISPLAY 0.340426 (-5280 4672);
PAINT GREEN (-5280 4672);
DISPLAY INVISIBLE (-5280 4672);
FORCEPROP 1 LAST BODY_TYPE PLUMBING
J 0
(-5370 4607);
DISPLAY 0.340426 (-5370 4607);
PAINT GREEN (-5370 4607);
DISPLAY INVISIBLE (-5370 4607);
FORCEPROP 1 LAST VOLTAGE 5.0V
J 0
(-5370 4607);
DISPLAY 0.340426 (-5370 4607);
PAINT SKYBLUE (-5370 4607);
DISPLAY INVISIBLE (-5370 4607);
FORCEPROP 1 LAST HDL_POWER P5V_STBY
J 0
(-5625 4525);
DISPLAY 0.872340 (-5625 4525);
PAINT ORANGE (-5625 4525);
DISPLAY INVISIBLE (-5625 4525);
FORCEADD CAP_A..1
(-775 3000);
FORCEPROP 1 LAST TOLERANCE 20%
J 0
(-725 2950);
DISPLAY 0.617021 (-725 2950);
PAINT SKYBLUE (-725 2950);
FORCEPROP 1 LAST PACK_TYPE 0603V
J 0
(-725 2800);
DISPLAY 0.617021 (-725 2800);
PAINT SKYBLUE (-725 2800);
FORCEPROP 1 LAST VOLTAGE 4V
J 0
(-725 3000);
DISPLAY 0.617021 (-725 3000);
PAINT SKYBLUE (-725 3000);
FORCEPROP 1 LAST MATERIAL X6S
J 0
(-725 2900);
DISPLAY 0.617021 (-725 2900);
PAINT SKYBLUE (-725 2900);
FORCEPROP 1 LASTPIN (-775 2900) $PN 2
J 0
(-765 2880);
DISPLAY 0.617021 (-765 2880);
PAINT ORANGE (-765 2880);
FORCEPROP 1 LAST PART_NUMBER E15431-004
J 0
(-725 2850);
DISPLAY 0.617021 (-725 2850);
PAINT BLUE (-725 2850);
FORCEPROP 1 LAST VALUE 22.0UF
J 0
(-725 3050);
DISPLAY 0.617021 (-725 3050);
PAINT SKYBLUE (-725 3050);
FORCEPROP 1 LASTPIN (-775 3100) $PN 1
J 0
(-765 3080);
DISPLAY 0.617021 (-765 3080);
PAINT ORANGE (-765 3080);
FORCEPROP 1 LAST LOCATION C6R2
J 0
(-725 3100);
DISPLAY 0.617021 (-725 3100);
PAINT AQUA (-725 3100);
FORCEPROP 1 LAST PATH I70
J 0
(-725 3150);
DISPLAY 0.978723 (-725 3150);
PAINT WHITE (-725 3150);
DISPLAY INVISIBLE (-725 3150);
FORCEPROP 2 LAST SEC 1
J 0
(-725 3200);
DISPLAY 0.680851 (-725 3200);
PAINT MONO (-725 3200);
DISPLAY INVISIBLE (-725 3200);
FORCEPROP 2 LAST SEC_TYPE 0603V
J 0
(-725 3200);
DISPLAY 1.021277 (-725 3200);
PAINT ORANGE (-725 3200);
DISPLAY INVISIBLE (-725 3200);
FORCEPROP 2 LAST CDS_SEC 1
J 0
(-725 3150);
PAINT ORANGE (-725 3150);
DISPLAY INVISIBLE (-725 3150);
FORCEPROP 2 LAST CDS_LOCATION C6R2
J 0
(-725 3100);
DISPLAY 0.617021 (-725 3100);
PAINT AQUA (-725 3100);
DISPLAY INVISIBLE (-725 3100);
FORCEPROP 2 LAST CDS_LIB dev_discrete
J 0
(-775 3000);
PAINT ORANGE (-775 3000);
DISPLAY INVISIBLE (-775 3000);
FORCEADD IR354XX..1
(-3500 3700);
FORCEPROP 1 LAST PART_NUMBER H73688-001
J 0
(-3875 3000);
DISPLAY 0.617021 (-3875 3000);
PAINT BLUE (-3875 3000);
FORCEPROP 2 LASTPIN (-4000 3500) $PN 39
J 2
(-4010 3510);
DISPLAY 0.617021 (-4010 3510);
PAINT MONO (-4010 3510);
FORCEPROP 2 LASTPIN (-4000 3350) $PN 32
J 2
(-4010 3360);
DISPLAY 0.617021 (-4010 3360);
PAINT MONO (-4010 3360);
FORCEPROP 2 LASTPIN (-4000 3400) $PN 33
J 2
(-4010 3410);
DISPLAY 0.617021 (-4010 3410);
PAINT MONO (-4010 3410);
FORCEPROP 2 LASTPIN (-4000 3600) $PN 34
J 2
(-4010 3610);
DISPLAY 0.617021 (-4010 3610);
PAINT MONO (-4010 3610);
FORCEPROP 2 LASTPIN (-4000 3750) $PN 41
J 2
(-4010 3760);
DISPLAY 0.617021 (-4010 3760);
PAINT MONO (-4010 3760);
FORCEPROP 2 LASTPIN (-4000 3700) $PN 6
J 2
(-4010 3710);
DISPLAY 0.617021 (-4010 3710);
PAINT MONO (-4010 3710);
FORCEPROP 2 LASTPIN (-4000 3850) $PN 1
J 2
(-4010 3860);
DISPLAY 0.617021 (-4010 3860);
PAINT MONO (-4010 3860);
FORCEPROP 2 LASTPIN (-4000 4050) $PN 4
J 2
(-4010 4060);
DISPLAY 0.617021 (-4010 4060);
PAINT MONO (-4010 4060);
FORCEPROP 2 LASTPIN (-4000 3950) $PN 35
J 2
(-4010 3960);
DISPLAY 0.617021 (-4010 3960);
PAINT MONO (-4010 3960);
FORCEPROP 2 LASTPIN (-3000 3200) $PN 7
J 0
(-2990 3210);
DISPLAY 0.617021 (-2990 3210);
PAINT MONO (-2990 3210);
FORCEPROP 2 LASTPIN (-3000 3150) $PN 5
J 0
(-2990 3160);
DISPLAY 0.617021 (-2990 3160);
PAINT MONO (-2990 3160);
FORCEPROP 2 LASTPIN (-3000 3250) $PN 40
J 0
(-2990 3260);
DISPLAY 0.617021 (-2990 3260);
PAINT MONO (-2990 3260);
FORCEPROP 2 LASTPIN (-3000 3300) $PN 2
J 0
(-2990 3310);
DISPLAY 0.617021 (-2990 3310);
PAINT MONO (-2990 3310);
FORCEPROP 2 LASTPIN (-3000 3400) $PN 10
J 0
(-2990 3410);
DISPLAY 0.617021 (-2990 3410);
PAINT MONO (-2990 3410);
FORCEPROP 2 LASTPIN (-3000 3750) $PN 36
J 0
(-2990 3760);
DISPLAY 0.617021 (-2990 3760);
PAINT MONO (-2990 3760);
FORCEPROP 2 LASTPIN (-3000 4050) $PN 37
J 0
(-2990 4060);
DISPLAY 0.617021 (-2990 4060);
PAINT MONO (-2990 4060);
FORCEPROP 2 LASTPIN (-3000 4000) $PN 31
J 0
(-2990 4010);
DISPLAY 0.617021 (-2990 4010);
PAINT MONO (-2990 4010);
FORCEPROP 2 LASTPIN (-4000 4250) $PN 3
J 2
(-4010 4260);
DISPLAY 0.617021 (-4010 4260);
PAINT MONO (-4010 4260);
FORCEPROP 2 LASTPIN (-4000 4200) $PN 30
J 2
(-4010 4210);
DISPLAY 0.617021 (-4010 4210);
PAINT MONO (-4010 4210);
FORCEPROP 2 LASTPIN (-4000 4150) $PN 25
J 2
(-4010 4160);
DISPLAY 0.617021 (-4010 4160);
PAINT MONO (-4010 4160);
FORCEPROP 1 LAST MATERIAL IC
J 0
(-3950 4450);
DISPLAY 0.617021 (-3950 4450);
PAINT SKYBLUE (-3950 4450);
FORCEPROP 1 LAST LOCATION EU4C2
J 0
(-3950 4500);
DISPLAY 0.617021 (-3950 4500);
PAINT AQUA (-3950 4500);
FORCEPROP 1 LAST VALUE IR35411
J 1
(-3500 4325);
DISPLAY 0.617021 (-3500 4325);
PAINT SKYBLUE (-3500 4325);
FORCEPROP 2 LASTPIN (-3000 4250) $PN 38
J 0
(-2990 4260);
DISPLAY 0.617021 (-2990 4260);
PAINT MONO (-2990 4260);
FORCEPROP 1 LAST PATH I71
J 0
(-3500 4450);
PAINT GREEN (-3500 4450);
DISPLAY INVISIBLE (-3500 4450);
FORCEPROP 2 LAST CDS_LOCATION EU4C2
J 0
(-3950 4500);
PAINT GREEN (-3950 4500);
DISPLAY INVISIBLE (-3950 4500);
FORCEPROP 2 LAST $SEC 1
J 0
(-3950 4550);
PAINT MONO (-3950 4550);
DISPLAY INVISIBLE (-3950 4550);
FORCEPROP 2 LAST CDS_SEC 1
J 0
(-3950 4550);
PAINT MONO (-3950 4550);
DISPLAY INVISIBLE (-3950 4550);
FORCEPROP 1 LAST PACK_TYPE SM
J 0
(-3950 4550);
PAINT SKYBLUE (-3950 4550);
DISPLAY INVISIBLE (-3950 4550);
FORCEPROP 2 LAST CDS_LIB mstr_discrete
J 0
(-3500 3700);
PAINT ORANGE (-3500 3700);
DISPLAY INVISIBLE (-3500 3700);
FORCEADD GND..1
(-775 2675);
FORCEPROP 3 LASTPIN (-775 2725) SIG_NAME GND\g
J 0
(-765 2735);
DISPLAY 0.659574 (-765 2735);
PAINT MONO (-765 2735);
DISPLAY INVISIBLE (-765 2735);
FORCEPROP 2 LAST ROOM PVCCIN_CPU0_PWR_VR
J 0
(-1325 2750);
DISPLAY 1.936170 (-1325 2750);
PAINT ORANGE (-1325 2750);
DISPLAY INVISIBLE (-1325 2750);
FORCEPROP 2 LAST BOM_COST PROC_VRD_VCCIN_CPU0
J 0
(-1150 2750);
DISPLAY 1.446809 (-1150 2750);
PAINT MONO (-1150 2750);
DISPLAY INVISIBLE (-1150 2750);
FORCEPROP 1 LAST PATH I8
J 0
(-700 2675);
DISPLAY 0.872340 (-700 2675);
PAINT AQUA (-700 2675);
DISPLAY INVISIBLE (-700 2675);
FORCEPROP 1 LAST BODY_TYPE PLUMBING
J 0
(-820 2632);
DISPLAY 0.340426 (-820 2632);
PAINT GREEN (-820 2632);
DISPLAY INVISIBLE (-820 2632);
FORCEPROP 1 LAST VOLTAGE 0
J 0
(-775 2675);
PAINT SKYBLUE (-775 2675);
DISPLAY INVISIBLE (-775 2675);
FORCEPROP 1 LAST SIZE 1B
J 0
(-700 2625);
DISPLAY 1.723404 (-700 2625);
PAINT GREEN (-700 2625);
DISPLAY INVISIBLE (-700 2625);
FORCEPROP 2 LAST CDS_LIB mstr_symbols
J 0
(-775 2675);
DISPLAY 1.936170 (-775 2675);
PAINT ORANGE (-775 2675);
DISPLAY INVISIBLE (-775 2675);
FORCEPROP 1 LAST HDL_POWER GND
J 0
(-775 2825);
DISPLAY 1.723404 (-775 2825);
PAINT GREEN (-775 2825);
DISPLAY INVISIBLE (-775 2825);
FORCEADD RES..2
(-775 3850);
FORCEPROP 1 LASTPIN (-775 3750) $PN 2
J 0
(-770 3760);
DISPLAY 0.617021 (-770 3760);
PAINT ORANGE (-770 3760);
FORCEPROP 1 LASTPIN (-775 3950) $PN 1
J 0
(-770 3912);
DISPLAY 0.617021 (-770 3912);
PAINT ORANGE (-770 3912);
FORCEPROP 1 LAST MATERIAL EMPTY
J 0
(-735 3775);
DISPLAY 0.617021 (-735 3775);
PAINT RED (-735 3775);
FORCEPROP 1 LAST PACK_TYPE 0402
J 0
(-735 3675);
DISPLAY 0.617021 (-735 3675);
PAINT SKYBLUE (-735 3675);
FORCEPROP 1 LAST WATTAGE 1/16W
J 0
(-735 3825);
DISPLAY 0.617021 (-735 3825);
PAINT SKYBLUE (-735 3825);
FORCEPROP 1 LAST TOLERANCE 1%
J 0
(-730 3875);
DISPLAY 0.617021 (-730 3875);
PAINT SKYBLUE (-730 3875);
FORCEPROP 1 LAST LOCATION R4D68
J 0
(-730 3975);
DISPLAY 0.617021 (-730 3975);
PAINT AQUA (-730 3975);
FORCEPROP 1 LAST VALUE 68.1K
J 0
(-730 3925);
DISPLAY 0.617021 (-730 3925);
PAINT SKYBLUE (-730 3925);
FORCEPROP 1 LAST PART_NUMBER G21796-187
J 0
(-735 3725);
DISPLAY 0.617021 (-735 3725);
PAINT BLUE (-735 3725);
FORCEPROP 2 LAST SEC_TYPE 0402
J 0
(-725 4075);
DISPLAY 1.021277 (-725 4075);
PAINT ORANGE (-725 4075);
DISPLAY INVISIBLE (-725 4075);
FORCEPROP 0 LAST SEC 1
J 0
(-725 4025);
DISPLAY 0.680851 (-725 4025);
PAINT MONO (-725 4025);
DISPLAY INVISIBLE (-725 4025);
FORCEPROP 1 LAST PATH I83
J 0
(-725 4025);
DISPLAY 0.978723 (-725 4025);
PAINT WHITE (-725 4025);
DISPLAY INVISIBLE (-725 4025);
FORCEPROP 2 LAST CDS_LIB mstr_discrete
J 0
(-775 3850);
PAINT ORANGE (-775 3850);
DISPLAY INVISIBLE (-775 3850);
FORCEADD GND..1
(-775 3625);
FORCEPROP 3 LASTPIN (-775 3675) SIG_NAME GND\g
J 0
(-765 3685);
DISPLAY 0.659574 (-765 3685);
PAINT MONO (-765 3685);
DISPLAY INVISIBLE (-765 3685);
FORCEPROP 1 LAST PATH I84
J 0
(-700 3625);
DISPLAY 0.872340 (-700 3625);
PAINT AQUA (-700 3625);
DISPLAY INVISIBLE (-700 3625);
FORCEPROP 1 LAST HDL_POWER GND
J 0
(-775 3775);
DISPLAY 1.723404 (-775 3775);
PAINT GREEN (-775 3775);
DISPLAY INVISIBLE (-775 3775);
FORCEPROP 1 LAST VOLTAGE 0
J 0
(-775 3625);
PAINT SKYBLUE (-775 3625);
DISPLAY INVISIBLE (-775 3625);
FORCEPROP 2 LAST CDS_LIB mstr_symbols
J 0
(-775 3625);
PAINT ORANGE (-775 3625);
DISPLAY INVISIBLE (-775 3625);
FORCEPROP 1 LAST SIZE 1B
J 0
(-700 3575);
DISPLAY 1.723404 (-700 3575);
PAINT GREEN (-700 3575);
DISPLAY INVISIBLE (-700 3575);
FORCEPROP 1 LAST BODY_TYPE PLUMBING
J 0
(-820 3582);
DISPLAY 0.340426 (-820 3582);
PAINT GREEN (-820 3582);
DISPLAY INVISIBLE (-820 3582);
FORCEPROP 2 LAST BOM_COST PROC_VRD_VCCIN_CPU0
J 0
(-1150 3700);
DISPLAY 1.446809 (-1150 3700);
PAINT MONO (-1150 3700);
DISPLAY INVISIBLE (-1150 3700);
FORCEPROP 2 LAST ROOM PVCCIN_CPU0_PWR_VR
J 0
(-1325 3700);
DISPLAY 1.936170 (-1325 3700);
PAINT ORANGE (-1325 3700);
DISPLAY INVISIBLE (-1325 3700);
FORCEADD CAP_A..1
(-4225 3200);
FORCEPROP 1 LAST LOCATION CT36
J 0
(-4375 3200);
DISPLAY 0.617021 (-4375 3200);
PAINT AQUA (-4375 3200);
FORCEPROP 0 LAST STATUS NOPOP
J 0
(-4500 3125);
DISPLAY 1.021277 (-4500 3125);
PAINT ORANGE (-4500 3125);
FORCEPROP 1 LAST VOLTAGE 16V
J 0
(-4175 3200);
DISPLAY 0.617021 (-4175 3200);
PAINT SKYBLUE (-4175 3200);
FORCEPROP 1 LAST TOLERANCE 10%
J 0
(-4175 3150);
DISPLAY 0.617021 (-4175 3150);
PAINT SKYBLUE (-4175 3150);
FORCEPROP 1 LAST MATERIAL X7R
J 0
(-4175 3100);
DISPLAY 0.617021 (-4175 3100);
PAINT SKYBLUE (-4175 3100);
FORCEPROP 1 LAST PACK_TYPE 0402V
J 0
(-4175 3000);
DISPLAY 0.617021 (-4175 3000);
PAINT SKYBLUE (-4175 3000);
FORCEPROP 1 LAST PART_NUMBER A36096-030
J 0
(-4175 3050);
DISPLAY 0.617021 (-4175 3050);
PAINT BLUE (-4175 3050);
FORCEPROP 1 LAST VALUE 0.1UF
J 0
(-4175 3250);
DISPLAY 0.617021 (-4175 3250);
PAINT SKYBLUE (-4175 3250);
FORCEPROP 1 LASTPIN (-4225 3100) $PN 2
J 0
(-4215 3080);
DISPLAY 0.787234 (-4215 3080);
PAINT ORANGE (-4215 3080);
DISPLAY INVISIBLE (-4215 3080);
FORCEPROP 1 LASTPIN (-4225 3300) $PN 1
J 0
(-4215 3280);
DISPLAY 0.787234 (-4215 3280);
PAINT ORANGE (-4215 3280);
DISPLAY INVISIBLE (-4215 3280);
FORCEPROP 2 LAST CDS_LIB dev_discrete
J 0
(-4225 3200);
PAINT MONO (-4225 3200);
DISPLAY INVISIBLE (-4225 3200);
FORCEPROP 1 LAST PATH I85
J 0
(-4175 3350);
DISPLAY 0.978723 (-4175 3350);
PAINT WHITE (-4175 3350);
DISPLAY INVISIBLE (-4175 3350);
FORCEPROP 2 LAST ROOM PVCCIN_CPU0_PWR_VR
J 0
(-4175 3350);
DISPLAY 1.361702 (-4175 3350);
PAINT ORANGE (-4175 3350);
DISPLAY INVISIBLE (-4175 3350);
FORCEADD GND..1
(-4225 2950);
FORCEPROP 3 LASTPIN (-4225 3000) SIG_NAME GND\g
J 0
(-4215 3010);
DISPLAY 0.659574 (-4215 3010);
PAINT MONO (-4215 3010);
DISPLAY INVISIBLE (-4215 3010);
FORCEPROP 2 LAST CDS_LIB mstr_symbols
J 0
(-4225 2950);
PAINT MONO (-4225 2950);
DISPLAY INVISIBLE (-4225 2950);
FORCEPROP 1 LAST PATH I86
J 0
(-4150 2950);
DISPLAY 0.872340 (-4150 2950);
PAINT AQUA (-4150 2950);
DISPLAY INVISIBLE (-4150 2950);
FORCEPROP 1 LAST HDL_POWER GND
J 0
(-4225 3100);
DISPLAY 1.723404 (-4225 3100);
PAINT GREEN (-4225 3100);
DISPLAY INVISIBLE (-4225 3100);
FORCEPROP 1 LAST VOLTAGE 0
J 0
(-4225 2950);
PAINT SKYBLUE (-4225 2950);
DISPLAY INVISIBLE (-4225 2950);
FORCEPROP 1 LAST SIZE 1B
J 0
(-4150 2900);
DISPLAY 1.723404 (-4150 2900);
PAINT GREEN (-4150 2900);
DISPLAY INVISIBLE (-4150 2900);
FORCEPROP 2 LAST BOM_COST PROC_VRD_VCCIN_CPU0
J 0
(-4600 3025);
DISPLAY 1.446809 (-4600 3025);
PAINT MONO (-4600 3025);
DISPLAY INVISIBLE (-4600 3025);
FORCEPROP 2 LAST ROOM PVCCIN_CPU0_PWR_VR
J 0
(-4775 3025);
DISPLAY 1.936170 (-4775 3025);
PAINT ORANGE (-4775 3025);
DISPLAY INVISIBLE (-4775 3025);
FORCEPROP 1 LAST BODY_TYPE PLUMBING
J 0
(-4270 2907);
DISPLAY 0.340426 (-4270 2907);
PAINT GREEN (-4270 2907);
DISPLAY INVISIBLE (-4270 2907);
FORCEADD CAP..1
(-2450 3725);
FORCEPROP 0 LAST STATUS NOPOP
J 0
(-2300 3700);
DISPLAY 1.021277 (-2300 3700);
PAINT ORANGE (-2300 3700);
FORCEPROP 1 LAST TOLERANCE 10%
J 0
(-2400 3675);
DISPLAY 0.617021 (-2400 3675);
PAINT SKYBLUE (-2400 3675);
FORCEPROP 1 LAST PART_NUMBER A36096-046
J 0
(-2400 3575);
DISPLAY 0.617021 (-2400 3575);
PAINT BLUE (-2400 3575);
FORCEPROP 1 LAST VALUE 1000PF
J 0
(-2400 3775);
DISPLAY 0.617021 (-2400 3775);
PAINT SKYBLUE (-2400 3775);
FORCEPROP 1 LAST PACK_TYPE 0402LF
J 0
(-2400 3525);
DISPLAY 0.617021 (-2400 3525);
PAINT SKYBLUE (-2400 3525);
FORCEPROP 1 LAST VOLTAGE 50V
J 0
(-2400 3725);
DISPLAY 0.617021 (-2400 3725);
PAINT SKYBLUE (-2400 3725);
FORCEPROP 1 LAST MATERIAL X7R
J 0
(-2400 3625);
DISPLAY 0.617021 (-2400 3625);
PAINT SKYBLUE (-2400 3625);
FORCEPROP 1 LAST LOCATION CT34
J 0
(-2400 3825);
DISPLAY 0.617021 (-2400 3825);
PAINT AQUA (-2400 3825);
FORCEPROP 1 LASTPIN (-2450 3825) $PN 1
J 0
(-2440 3805);
DISPLAY 0.787234 (-2440 3805);
PAINT ORANGE (-2440 3805);
DISPLAY INVISIBLE (-2440 3805);
FORCEPROP 1 LASTPIN (-2450 3625) $PN 2
J 0
(-2440 3605);
DISPLAY 0.787234 (-2440 3605);
PAINT ORANGE (-2440 3605);
DISPLAY INVISIBLE (-2440 3605);
FORCEPROP 2 LAST CDS_LIB mstr_discrete
J 0
(-2450 3725);
PAINT MONO (-2450 3725);
DISPLAY INVISIBLE (-2450 3725);
FORCEPROP 1 LAST PATH I88
J 0
(-2400 3875);
DISPLAY 0.978723 (-2400 3875);
PAINT WHITE (-2400 3875);
DISPLAY INVISIBLE (-2400 3875);
FORCEPROP 0 LAST ROOM VDDQ_KLM_PWR_VR
J 0
(-2400 3925);
DISPLAY 1.021277 (-2400 3925);
PAINT ORANGE (-2400 3925);
DISPLAY INVISIBLE (-2400 3925);
FORCEADD GND..1
(-2450 3525);
FORCEPROP 3 LASTPIN (-2450 3575) SIG_NAME GND\g
J 0
(-2440 3585);
DISPLAY 0.659574 (-2440 3585);
PAINT MONO (-2440 3585);
DISPLAY INVISIBLE (-2440 3585);
FORCEPROP 2 LAST CDS_LIB mstr_symbols
J 0
(-2450 3525);
PAINT MONO (-2450 3525);
DISPLAY INVISIBLE (-2450 3525);
FORCEPROP 1 LAST PATH I89
J 0
(-2375 3525);
DISPLAY 0.872340 (-2375 3525);
PAINT AQUA (-2375 3525);
DISPLAY INVISIBLE (-2375 3525);
FORCEPROP 2 LAST ROOM VDDQ_KLM_PWR_VR
J 0
(-3025 3600);
DISPLAY 1.361702 (-3025 3600);
PAINT ORANGE (-3025 3600);
DISPLAY INVISIBLE (-3025 3600);
FORCEPROP 1 LAST VOLTAGE 0
J 0
(-2450 3525);
PAINT SKYBLUE (-2450 3525);
DISPLAY INVISIBLE (-2450 3525);
FORCEPROP 1 LAST BODY_TYPE PLUMBING
J 0
(-2495 3482);
DISPLAY 0.340426 (-2495 3482);
PAINT GREEN (-2495 3482);
DISPLAY INVISIBLE (-2495 3482);
FORCEPROP 1 LAST SIZE 1B
J 0
(-2375 3475);
DISPLAY 1.170213 (-2375 3475);
PAINT AQUA (-2375 3475);
DISPLAY INVISIBLE (-2375 3475);
FORCEPROP 1 LAST HDL_POWER GND
J 0
(-2450 3675);
DISPLAY 1.170213 (-2450 3675);
PAINT GREEN (-2450 3675);
DISPLAY INVISIBLE (-2450 3675);
FORCEADD CAP_A..1
(-1100 3100);
FORCEPROP 1 LAST LOCATION C4D12
J 0
(-1050 3200);
DISPLAY 0.617021 (-1050 3200);
PAINT AQUA (-1050 3200);
FORCEPROP 1 LAST VALUE 22.0UF
J 0
(-1050 3150);
DISPLAY 0.617021 (-1050 3150);
PAINT SKYBLUE (-1050 3150);
FORCEPROP 1 LAST TOLERANCE 20%
J 0
(-1050 3050);
DISPLAY 0.617021 (-1050 3050);
PAINT SKYBLUE (-1050 3050);
FORCEPROP 1 LASTPIN (-1100 3000) $PN 2
J 0
(-1090 2980);
DISPLAY 0.617021 (-1090 2980);
PAINT GREEN (-1090 2980);
FORCEPROP 1 LASTPIN (-1100 3200) $PN 1
J 0
(-1090 3180);
DISPLAY 0.617021 (-1090 3180);
PAINT GREEN (-1090 3180);
FORCEPROP 1 LAST PART_NUMBER E15431-004
J 0
(-1050 2950);
DISPLAY 0.617021 (-1050 2950);
PAINT BLUE (-1050 2950);
FORCEPROP 1 LAST PACK_TYPE 0603V
J 0
(-1050 2900);
DISPLAY 0.617021 (-1050 2900);
PAINT SKYBLUE (-1050 2900);
FORCEPROP 1 LAST VOLTAGE 4V
J 0
(-1050 3100);
DISPLAY 0.617021 (-1050 3100);
PAINT SKYBLUE (-1050 3100);
FORCEPROP 1 LAST MATERIAL X6S
J 0
(-1050 3000);
DISPLAY 0.617021 (-1050 3000);
PAINT SKYBLUE (-1050 3000);
FORCEPROP 2 LAST SEC 1
J 0
(-1045 3300);
DISPLAY 0.680851 (-1045 3300);
PAINT MONO (-1045 3300);
DISPLAY INVISIBLE (-1045 3300);
FORCEPROP 2 LAST SEC_TYPE 0603V
J 0
(-1045 3300);
DISPLAY 1.021277 (-1045 3300);
PAINT ORANGE (-1045 3300);
DISPLAY INVISIBLE (-1045 3300);
FORCEPROP 2 LAST ROOM PVCCIN_CPU0_PWR_VR
J 0
(-1050 3250);
DISPLAY 1.446809 (-1050 3250);
PAINT MONO (-1050 3250);
DISPLAY INVISIBLE (-1050 3250);
FORCEPROP 1 LAST PATH I9
J 0
(-1050 3250);
DISPLAY 0.978723 (-1050 3250);
PAINT WHITE (-1050 3250);
DISPLAY INVISIBLE (-1050 3250);
FORCEPROP 2 LAST CDS_SEC 1
J 0
(-1050 3250);
PAINT ORANGE (-1050 3250);
DISPLAY INVISIBLE (-1050 3250);
FORCEPROP 2 LAST CDS_LIB dev_discrete
J 0
(-1100 3100);
PAINT ORANGE (-1100 3100);
DISPLAY INVISIBLE (-1100 3100);
FORCEPROP 2 LAST BOM_COST PROC_VRD_VCCIN_CPU0
J 0
(-1050 3250);
DISPLAY 1.446809 (-1050 3250);
PAINT MONO (-1050 3250);
DISPLAY INVISIBLE (-1050 3250);
FORCEPROP 2 LAST CDS_LOCATION C4D12
J 0
(-1050 3200);
DISPLAY 0.617021 (-1050 3200);
PAINT AQUA (-1050 3200);
DISPLAY INVISIBLE (-1050 3200);
FORCEADD SC2K2P50V3KX-GP..1
(-2350 3275);
FORCEPROP 0 LAST STATUS NOPOP
J 0
(-2325 3175);
DISPLAY 1.021277 (-2325 3175);
PAINT ORANGE (-2325 3175);
FORCEPROP 1 LAST VALUE SC2K2P50V3KX-GP
J 0
(-2325 3225);
DISPLAY 0.617021 (-2325 3225);
PAINT GREEN (-2325 3225);
FORCEPROP 1 LAST LOCATION CT35
J 0
(-2325 3305);
DISPLAY 0.617021 (-2325 3305);
PAINT GREEN (-2325 3305);
FORCEPROP 1 LAST PART_NUMBER 78.22224.2BL
J 0
(-2350 3275);
DISPLAY 0.617021 (-2350 3275);
PAINT GREEN (-2350 3275);
DISPLAY INVISIBLE (-2350 3275);
FORCEPROP 1 LAST PACK_TYPE SMD-BCG6
J 0
(-2350 3275);
DISPLAY 0.617021 (-2350 3275);
PAINT GREEN (-2350 3275);
DISPLAY INVISIBLE (-2350 3275);
FORCEPROP 1 LAST CDS_LMAN_SYM_OUTLINE -50,25,50,-25
J 0
(-2350 3275);
DISPLAY 0.468085 (-2350 3275);
PAINT GREEN (-2350 3275);
DISPLAY INVISIBLE (-2350 3275);
FORCEPROP 1 LAST PATH I90
J 0
(-2350 3275);
DISPLAY 0.617021 (-2350 3275);
PAINT GREEN (-2350 3275);
DISPLAY INVISIBLE (-2350 3275);
FORCEPROP 2 LAST CDS_LIB w_hdl
J 0
(-2350 3275);
PAINT MONO (-2350 3275);
DISPLAY INVISIBLE (-2350 3275);
FORCEADD 3D01R5F-GP..1
R 4
(-2350 2975);
FORCEPROP 0 LAST STATUS NOPOP
J 0
(-2300 2925);
DISPLAY 1.021277 (-2300 2925);
PAINT ORANGE (-2300 2925);
FORCEPROP 1 LAST VALUE 3D01R5F-GP
J 0
(-2325 2975);
DISPLAY 0.617021 (-2325 2975);
PAINT GREEN (-2325 2975);
FORCEPROP 1 LAST LOCATION RT24
J 0
(-2475 2945);
DISPLAY 0.617021 (-2475 2945);
PAINT GREEN (-2475 2945);
FORCEPROP 2 LASTPIN (-2350 3100) SIG_NAME UN$204$3D01R5F-GP$I91$2
J 0
(-2340 3110);
DISPLAY 0.659574 (-2340 3110);
PAINT MONO (-2340 3110);
DISPLAY INVISIBLE (-2340 3110);
FORCEPROP 1 LAST PACK_TYPE SMD-RG5
R 2
J 0
(-2350 2975);
DISPLAY 0.617021 (-2350 2975);
PAINT GREEN (-2350 2975);
DISPLAY INVISIBLE (-2350 2975);
FORCEPROP 1 LAST PART_NUMBER 64.3R015.16L
R 2
J 0
(-2350 2975);
DISPLAY 0.617021 (-2350 2975);
PAINT GREEN (-2350 2975);
DISPLAY INVISIBLE (-2350 2975);
FORCEPROP 2 LAST CDS_LIB w_hdl
J 0
(-2350 2975);
PAINT MONO (-2350 2975);
DISPLAY INVISIBLE (-2350 2975);
FORCEPROP 1 LAST PATH I91
R 2
J 0
(-2350 2975);
DISPLAY 0.617021 (-2350 2975);
PAINT GREEN (-2350 2975);
DISPLAY INVISIBLE (-2350 2975);
FORCEPROP 1 LAST CDS_LMAN_SYM_OUTLINE -50,75,50,-75
R 2
J 0
(-2350 2975);
DISPLAY 0.468085 (-2350 2975);
PAINT GREEN (-2350 2975);
DISPLAY INVISIBLE (-2350 2975);
FORCEADD GND..1
(-2350 2750);
FORCEPROP 3 LASTPIN (-2350 2800) SIG_NAME GND\g
J 0
(-2340 2810);
DISPLAY 0.659574 (-2340 2810);
PAINT MONO (-2340 2810);
DISPLAY INVISIBLE (-2340 2810);
FORCEPROP 2 LAST CDS_LIB mstr_symbols
J 0
(-2350 2750);
PAINT MONO (-2350 2750);
DISPLAY INVISIBLE (-2350 2750);
FORCEPROP 1 LAST PATH I92
J 0
(-2275 2750);
DISPLAY 0.872340 (-2275 2750);
PAINT AQUA (-2275 2750);
DISPLAY INVISIBLE (-2275 2750);
FORCEPROP 1 LAST HDL_POWER GND
J 0
(-2350 2900);
DISPLAY 1.723404 (-2350 2900);
PAINT GREEN (-2350 2900);
DISPLAY INVISIBLE (-2350 2900);
FORCEPROP 1 LAST SIZE 1B
J 0
(-2275 2700);
DISPLAY 1.723404 (-2275 2700);
PAINT GREEN (-2275 2700);
DISPLAY INVISIBLE (-2275 2700);
FORCEPROP 1 LAST VOLTAGE 0
J 0
(-2350 2750);
PAINT SKYBLUE (-2350 2750);
DISPLAY INVISIBLE (-2350 2750);
FORCEPROP 1 LAST BODY_TYPE PLUMBING
J 0
(-2395 2707);
DISPLAY 0.340426 (-2395 2707);
PAINT GREEN (-2395 2707);
DISPLAY INVISIBLE (-2395 2707);
FORCEPROP 2 LAST BOM_COST PROC_VRD_VCCIN_CPU0
J 0
(-2725 2825);
DISPLAY 1.446809 (-2725 2825);
PAINT MONO (-2725 2825);
DISPLAY INVISIBLE (-2725 2825);
FORCEPROP 2 LAST ROOM PVCCIN_CPU0_PWR_VR
J 0
(-2900 2825);
DISPLAY 1.936170 (-2900 2825);
PAINT ORANGE (-2900 2825);
DISPLAY INVISIBLE (-2900 2825);
FORCEADD RES..1
(-5275 3500);
FORCEPROP 1 LAST PACK_TYPE 0402
J 0
(-5175 3350);
DISPLAY 0.617021 (-5175 3350);
PAINT SKYBLUE (-5175 3350);
FORCEPROP 1 LAST MATERIAL CHIP
J 0
(-5275 3350);
DISPLAY 0.617021 (-5275 3350);
PAINT SKYBLUE (-5275 3350);
FORCEPROP 1 LAST TOLERANCE 5%
J 0
(-5275 3400);
DISPLAY 0.617021 (-5275 3400);
PAINT SKYBLUE (-5275 3400);
FORCEPROP 1 LAST PART_NUMBER G21497-005
J 0
(-5375 3450);
DISPLAY 0.617021 (-5375 3450);
PAINT BLUE (-5375 3450);
FORCEPROP 1 LAST VALUE 0.0
J 2
(-5300 3400);
DISPLAY 0.617021 (-5300 3400);
PAINT SKYBLUE (-5300 3400);
FORCEPROP 1 LAST WATTAGE 1/16W
J 2
(-5300 3350);
DISPLAY 0.617021 (-5300 3350);
PAINT SKYBLUE (-5300 3350);
FORCEPROP 1 LAST LOCATION RT23
J 0
(-5325 3525);
DISPLAY 0.617021 (-5325 3525);
PAINT AQUA (-5325 3525);
FORCEPROP 2 LAST ROOM BMC_DEBUG_HEADER
J 0
(-5325 3650);
DISPLAY 1.021277 (-5325 3650);
PAINT ORANGE (-5325 3650);
DISPLAY INVISIBLE (-5325 3650);
FORCEPROP 2 LAST BOM_COST DEBUG
J 0
(-5325 3700);
DISPLAY 1.021277 (-5325 3700);
PAINT ORANGE (-5325 3700);
DISPLAY INVISIBLE (-5325 3700);
FORCEPROP 1 LAST PATH I93
J 0
(-5325 3650);
DISPLAY 0.978723 (-5325 3650);
PAINT WHITE (-5325 3650);
DISPLAY INVISIBLE (-5325 3650);
FORCEPROP 2 LAST CDS_LIB mstr_discrete
J 0
(-5275 3500);
PAINT MONO (-5275 3500);
DISPLAY INVISIBLE (-5275 3500);
FORCEPROP 1 LASTPIN (-5375 3500) $PN 1
J 0
(-5363 3512);
DISPLAY 0.787234 (-5363 3512);
PAINT ORANGE (-5363 3512);
DISPLAY INVISIBLE (-5363 3512);
FORCEPROP 1 LASTPIN (-5175 3500) $PN 2
J 0
(-5213 3512);
DISPLAY 0.787234 (-5213 3512);
PAINT ORANGE (-5213 3512);
DISPLAY INVISIBLE (-5213 3512);
FORCEADD DNS..2
(-6270 1620);
PAINT RED (-6270 1620);
FORCEPROP 2 LAST CDS_LIB mstr_misc
J 0
(-6270 1620);
PAINT ORANGE (-6270 1620);
DISPLAY INVISIBLE (-6270 1620);
FORCEPROP 1 LAST COMMENT_BODY TRUE
R 1
J 0
(-6195 1395);
DISPLAY 0.872340 (-6195 1395);
PAINT GREEN (-6195 1395);
DISPLAY INVISIBLE (-6195 1395);
FORCEADD DESIGN_NOTE..1
(-7550 3000);
PAINT PURPLE (-7550 3000);
FORCEPROP 1 LAST COMMENT_BODY TRUE
J 0
(-7525 3100);
DISPLAY 1.319149 (-7525 3100);
PAINT GREEN (-7525 3100);
DISPLAY INVISIBLE (-7525 3100);
FORCEPROP 2 LAST CDS_LIB mstr_symbols
J 0
(-7550 3000);
PAINT ORANGE (-7550 3000);
DISPLAY INVISIBLE (-7550 3000);
FORCEPROP 2 LAST ROOM PVCCIN_CPU0_VR
J 0
(-7750 2950);
PAINT MONO (-7750 2950);
DISPLAY INVISIBLE (-7750 2950);
FORCEPROP 2 LAST BOM_COST SM_CONTROLLER
J 0
(-7750 2950);
PAINT MONO (-7750 2950);
DISPLAY INVISIBLE (-7750 2950);
FORCEADD DNS..7
(-2745 1270);
PAINT RED (-2745 1270);
FORCEPROP 2 LAST CDS_LIB mstr_misc
J 0
(-2745 1270);
PAINT ORANGE (-2745 1270);
DISPLAY INVISIBLE (-2745 1270);
FORCEPROP 1 LAST COMMENT_BODY TRUE
R 1
J 0
(-2670 1045);
DISPLAY 0.872340 (-2670 1045);
PAINT GREEN (-2670 1045);
DISPLAY INVISIBLE (-2670 1045);
FORCEADD DNS..2
(-2220 1045);
PAINT RED (-2220 1045);
FORCEPROP 2 LAST CDS_LIB mstr_misc
J 0
(-2220 1045);
PAINT ORANGE (-2220 1045);
DISPLAY INVISIBLE (-2220 1045);
FORCEPROP 1 LAST COMMENT_BODY TRUE
R 1
J 0
(-2145 820);
DISPLAY 0.872340 (-2145 820);
PAINT GREEN (-2145 820);
DISPLAY INVISIBLE (-2145 820);
FORCEADD DNS..2
(-770 3845);
PAINT RED (-770 3845);
FORCEPROP 2 LAST CDS_LIB mstr_misc
J 0
(-770 3845);
PAINT ORANGE (-770 3845);
DISPLAY INVISIBLE (-770 3845);
FORCEPROP 1 LAST COMMENT_BODY TRUE
R 1
J 0
(-695 3620);
DISPLAY 0.872340 (-695 3620);
PAINT GREEN (-695 3620);
DISPLAY INVISIBLE (-695 3620);
FORCEADD INTEL_CORP_BPAGE..1
(0 0);
FORCEPROP 1 LAST CDS_CON_LAST_MODIFIED Tue Dec 01 11:52:22 2015
J 0
(-1425 325);
PAINT ORANGE (-1425 325);
DISPLAY INVISIBLE (-1425 325);
FORCEPROP 1 LAST CUSTOM_TXT_CDS <CURRENT_DESIGN_SHEET> OF <TOTAL_DESIGN_SHEETS>
J 0
(-500 25);
PAINT GREEN (-500 25);
FORCEPROP 1 LAST CUSTOM_TXT_CDS <CON_LAST_MODIFIED>
J 0
(-1925 350);
PAINT GREEN (-1925 350);
FORCEPROP 2 LAST CUSTOM_TXT_CDS <XR_PAGE_TITLE>
J 0
(-7890 5250);
DISPLAY 0.638298 (-7890 5250);
PAINT PINK (-7890 5250);
DISPLAY INVISIBLE (-7890 5250);
FORCEPROP 1 LAST SCH_TITLE VCCIN CPU0 (4 OF 4)
J 0
(-7950 50);
DISPLAY 1.212766 (-7950 50);
PAINT ORANGE (-7950 50);
FORCEPROP 1 LAST SCH_DEPT BESD
J 1
(-4450 100);
DISPLAY 1.212766 (-4450 100);
PAINT YELLOW (-4450 100);
FORCEPROP 1 LAST SCH_ADDRESS3 Santa Clara, CA 95052-8119
J 0
(-3975 25);
DISPLAY 0.617021 (-3975 25);
PAINT GREEN (-3975 25);
FORCEPROP 1 LAST SCH_ADDRESS2 P.O. BOX 58119
J 0
(-3975 75);
DISPLAY 0.617021 (-3975 75);
PAINT GREEN (-3975 75);
FORCEPROP 1 LAST SCH_ADDRESS1 2200 Mission College Blvd.
J 0
(-3975 125);
DISPLAY 0.617021 (-3975 125);
PAINT GREEN (-3975 125);
FORCEPROP 1 LAST SCH_NUMBER H4694802
J 0
(-1300 150);
DISPLAY 1.212766 (-1300 150);
PAINT YELLOW (-1300 150);
FORCEPROP 1 LAST SCH_REV 2.420
J 0
(-250 150);
DISPLAY 0.978723 (-250 150);
PAINT YELLOW (-250 150);
FORCEPROP 1 LAST COMMENT_BODY TRUE
J 0
(12 12);
DISPLAY 0.468085 (12 12);
PAINT GREEN (12 12);
DISPLAY INVISIBLE (12 12);
FORCEPROP 2 LAST CDS_LIB mstr_symbols
J 0
(0 0);
PAINT MONO (0 0);
DISPLAY INVISIBLE (0 0);
FORCEPROP 2 LAST PAGE_BORDER TRUE
J 0
(-7890 5250);
DISPLAY 0.638298 (-7890 5250);
PAINT PINK (-7890 5250);
DISPLAY INVISIBLE (-7890 5250);
FORCEPROP 2 LAST CDS_XR_PAGE_TITLE CR-204 : @BASEBOARD_FAB2_LIB.BASEBOARD_FAB2(SCH_1):PAGE204
J 0
(-7890 5250);
DISPLAY 0.638298 (-7890 5250);
PAINT PINK (-7890 5250);
DISPLAY INVISIBLE (-7890 5250);
WIRE 16 -1 (-3000 3300)(-2850 3300);
WIRE 16 -1 (-2850 3250)(-2850 3300);
WIRE 16 -1 (-2850 3200)(-2850 3250);
WIRE 16 -1 (-2850 3250)(-3000 3250);
WIRE 16 -1 (-2850 3150)(-2850 3200);
WIRE 16 -1 (-2850 3200)(-3000 3200);
WIRE 16 -1 (-2850 3100)(-2850 3150);
WIRE 16 -1 (-2850 3150)(-3000 3150);
WIRE 16 -1 (-4000 3850)(-4100 3850);
WIRE 16 -1 (-4100 3850)(-4100 2675);
WIRE 16 -1 (-4100 2675)(-1525 2675);
WIRE 16 -1 (-1525 2675)(-1525 3400);
WIRE 16 -1 (-1825 3400)(-1525 3400);
WIRE 16 -1 (-1525 3400)(-1100 3400);
WIRE 16 -1 (-1100 3200)(-1100 3400);
WIRE 16 -1 (-775 3400)(-1100 3400);
WIRE 16 -1 (-775 3100)(-775 3400);
WIRE 16 -1 (-775 3400)(-775 3450);
WIRE 16 -1 (-4000 4150)(-4100 4150);
WIRE 16 -1 (-4100 4200)(-4100 4150);
WIRE 16 -1 (-4000 4200)(-4100 4200);
WIRE 16 -1 (-6650 4200)(-4100 4200);
WIRE 16 -1 (-6650 4075)(-6650 4200);
WIRE 16 -1 (-6650 4200)(-6875 4200);
WIRE 16 -1 (-6875 4025)(-6875 4200);
WIRE 16 -1 (-6875 4200)(-7100 4200);
WIRE 16 -1 (-7100 4075)(-7100 4200);
WIRE 16 -1 (-7100 4200)(-7325 4200);
WIRE 16 -1 (-7325 4025)(-7325 4200);
WIRE 16 -1 (-7325 4200)(-7550 4200);
WIRE 16 -1 (-7550 4050)(-7550 4200);
WIRE 16 -1 (-7550 4250)(-7550 4200);
WIRE 16 -1 (-5675 3875)(-5675 3650);
WIRE 16 -1 (-5675 3650)(-5825 3650);
WIRE 16 -1 (-5825 3875)(-5825 3650);
WIRE 16 -1 (-5825 3650)(-6425 3650);
WIRE 16 -1 (-6425 3850)(-6425 3650);
WIRE 16 -1 (-6425 3650)(-6650 3650);
WIRE 16 -1 (-6650 3875)(-6650 3650);
WIRE 16 -1 (-6650 3650)(-6875 3650);
WIRE 16 -1 (-6875 3825)(-6875 3650);
WIRE 16 -1 (-6875 3650)(-7100 3650);
WIRE 16 -1 (-7100 3875)(-7100 3650);
WIRE 16 -1 (-7100 3650)(-7325 3650);
WIRE 16 -1 (-7325 3825)(-7325 3650);
WIRE 16 -1 (-7325 3650)(-7550 3650);
WIRE 16 -1 (-7550 3850)(-7550 3650);
WIRE 16 -1 (-7550 3600)(-7550 3650);
WIRE 16 -1 (-1600 1225)(-1600 2175);
WIRE 16 -1 (-1600 1225)(-2400 1225);
WIRE 16 -1 (-1725 2175)(-1600 2175);
WIRE 16 -1 (-1600 2175)(-1400 2175);
WIRE 16 -1 (-1400 2100)(-1400 2175);
WIRE 16 -1 (-1400 2175)(-925 2175);
WIRE 16 -1 (-925 2075)(-925 2175);
WIRE 16 -1 (-575 2175)(-925 2175);
WIRE 16 -1 (-575 2075)(-575 2175);
WIRE 16 -1 (-575 2400)(-575 2175);
WIRE 16 -1 (-575 1875)(-575 1700);
WIRE 16 -1 (-575 1700)(-925 1700);
WIRE 16 -1 (-925 1875)(-925 1700);
WIRE 16 -1 (-925 1700)(-1175 1700);
WIRE 16 -1 (-1175 1700)(-1400 1700);
WIRE 16 -1 (-1175 1625)(-1175 1700);
WIRE 16 -1 (-1400 1900)(-1400 1700);
WIRE 16 -1 (-2225 950)(-2225 850);
WIRE 16 -1 (-3100 1175)(-3275 1175);
WIRE 16 -1 (-3275 1175)(-3275 1125);
WIRE 16 -1 (-3100 1125)(-3275 1125);
WIRE 16 -1 (-3275 1125)(-3275 1000);
WIRE 16 -1 (-5375 2225)(-4625 2225);
WIRE 16 -1 (-4625 2225)(-4625 2325);
WIRE 16 -1 (-4800 750)(-4800 975);
WIRE 16 -1 (-4800 975)(-5350 975);
WIRE 16 -1 (-3325 2375)(-3325 2175);
WIRE 16 -1 (-3325 2175)(-3075 2175);
WIRE 16 -1 (-4000 3950)(-4100 3950);
WIRE 16 -1 (-4100 3950)(-4100 4050);
WIRE 16 -1 (-4000 4050)(-4100 4050);
WIRE 16 -1 (-4100 4050)(-5325 4050);
WIRE 16 -1 (-5325 4050)(-5325 4525);
WIRE 16 -1 (-5325 4525)(-5675 4525);
WIRE 16 -1 (-5325 4525)(-5325 4600);
WIRE 16 -1 (-5675 4525)(-5825 4525);
WIRE 16 -1 (-5675 4075)(-5675 4525);
WIRE 16 -1 (-5825 4075)(-5825 4525);
WIRE 16 -1 (-5825 4525)(-6000 4525);
WIRE 16 -1 (-1100 3000)(-1100 2825);
WIRE 16 -1 (-775 2825)(-1100 2825);
WIRE 16 -1 (-775 2900)(-775 2825);
WIRE 16 -1 (-775 2725)(-775 2825);
WIRE 16 -1 (-775 3750)(-775 3675);
WIRE 16 -1 (-4225 3100)(-4225 3000);
WIRE 16 -1 (-2450 3575)(-2450 3625);
WIRE 16 -1 (-2350 2850)(-2350 2800);
WIRE 3 2175 (-2500 3450)(-2075 3450);
WIRE 3 2175 (-2500 3450)(-2500 2725);
WIRE 3 2175 (-2075 3450)(-2075 2725);
WIRE 3 2175 (-2500 2725)(-2075 2725);
WIRE 16 2175 (-6550 3100)(-5600 3100);
WIRE 16 2175 (-6550 3550)(-6550 3100);
WIRE 16 2175 (-5600 3550)(-5600 3100);
WIRE 16 2175 (-6550 3550)(-5600 3550);
WIRE 16 -1 (-3000 4000)(-2350 4000);
FORCEPROP 2 LAST SIG_NAME NC_PVCCIN_CPU0_PH5_P31
J 0
(-2908 4010);
DISPLAY 0.617021 (-2908 4010);
PAINT ORANGE (-2908 4010);
FORCEPROP 2 LASTPROP $XRERR UNIQUE?
J 0
(-2320 4000);
DISPLAY 0.638298 (-2320 4000);
PAINT MONO (-2320 4000);
DISPLAY INVISIBLE (-2320 4000);
WIRE 16 -1 (-2450 3825)(-2450 3900);
WIRE 16 -1 (-2450 3900)(-1925 3900);
WIRE 16 -1 (-3000 3900)(-2450 3900);
FORCEPROP 2 LAST SIG_NAME A_TSENSE_PVCCIN_CPU0
J 0
(-2961 3910);
DISPLAY 0.617021 (-2961 3910);
PAINT ORANGE (-2961 3910);
WIRE 16 -1 (-3000 3900)(-3000 3750);
WIRE 16 -1 (-6200 3225)(-4475 3225);
FORCEPROP 0 LAST VOLTAGE 5
J 0
(-6100 3300);
DISPLAY 1.021277 (-6100 3300);
PAINT SKYBLUE (-6100 3300);
DISPLAY INVISIBLE (-6100 3300);
FORCEPROP 2 LAST SIG_NAME VR_PVCCIN_CPU0_PH5_PHASE
J 0
(-6121 3235);
DISPLAY 0.617021 (-6121 3235);
PAINT ORANGE (-6121 3235);
FORCEPROP 2 LASTPROP $XRERR UNIQUE?
J 0
(-6361 3235);
DISPLAY 0.638298 (-6361 3235);
PAINT MONO (-6361 3235);
DISPLAY INVISIBLE (-6361 3235);
WIRE 16 -1 (-6200 3225)(-6200 3250);
WIRE 16 -1 (-4475 3225)(-4475 3350);
WIRE 16 -1 (-4475 3350)(-4000 3350);
WIRE 16 -1 (-6775 3600)(-4000 3600);
WIRE 16 -1 (-4975 3700)(-4000 3700);
FORCEPROP 0 LAST SIG_NAME TP_PVCCIN_CPU0_PH5_GL_0
J 0
(-4948 3715);
DISPLAY 0.617021 (-4948 3715);
PAINT ORANGE (-4948 3715);
FORCEPROP 2 LASTPROP $XRERR UNIQUE?
J 0
(-5215 3700);
DISPLAY 0.638298 (-5215 3700);
PAINT MONO (-5215 3700);
DISPLAY INVISIBLE (-5215 3700);
WIRE 16 -1 (-4975 3750)(-4000 3750);
FORCEPROP 0 LAST SIG_NAME TP_PVCCIN_CPU0_PH5_GL_1
J 0
(-4948 3765);
DISPLAY 0.617021 (-4948 3765);
PAINT ORANGE (-4948 3765);
FORCEPROP 2 LASTPROP $XRERR UNIQUE?
J 0
(-5215 3750);
DISPLAY 0.638298 (-5215 3750);
PAINT MONO (-5215 3750);
DISPLAY INVISIBLE (-5215 3750);
WIRE 3 2175 (-2525 3950)(-2075 3950);
WIRE 3 2175 (-2525 3950)(-2525 3475);
WIRE 3 2175 (-2075 3950)(-2075 3475);
WIRE 3 2175 (-2525 3475)(-2075 3475);
WIRE 3 2175 (-4550 2900)(-3925 2900);
WIRE 3 2175 (-4550 3475)(-4550 2900);
WIRE 3 2175 (-3925 3475)(-3925 2900);
WIRE 3 2175 (-4550 3475)(-3925 3475);
WIRE 16 -1 (-2225 1375)(-2225 2175);
WIRE 16 -1 (-2225 1150)(-2225 1375);
WIRE 16 -1 (-2225 1375)(-2400 1375);
WIRE 16 -1 (-2225 2175)(-2050 2175);
WIRE 16 -1 (-2875 2175)(-2225 2175);
FORCEPROP 2 LAST SIG_NAME VR_FET_SW_P12V_PVCCIN_CPU0_R
J 0
(-2774 2200);
DISPLAY 0.617021 (-2774 2200);
PAINT ORANGE (-2774 2200);
FORCEPROP 2 LASTPROP $XRERR UNIQUE?
J 0
(-3014 2200);
DISPLAY 0.638298 (-3014 2200);
PAINT MONO (-3014 2200);
DISPLAY INVISIBLE (-3014 2200);
WIRE 16 -1 (-2050 2175)(-1925 2175);
WIRE 16 -1 (-2050 1275)(-2050 2175);
WIRE 16 -1 (-2050 1275)(-2400 1275);
WIRE 16 -1 (-2350 3100)(-2350 3200);
WIRE 16 -1 (-4000 3500)(-4225 3500);
WIRE 16 -1 (-4225 3500)(-4225 4575);
WIRE 16 -1 (-4225 3300)(-4225 3500);
WIRE 16 -1 (-4225 4575)(-1475 4575);
FORCEPROP 2 LAST SIG_NAME VR_PVCCIN_CPU0_AIREF5
J 0
(-2001 4583);
DISPLAY 0.617021 (-2001 4583);
PAINT ORANGE (-2001 4583);
WIRE 16 -1 (-5175 3500)(-4475 3500);
FORCEPROP 2 LAST SIG_NAME VR_PVCCIN_CPU0_PH5_BOOT_R
J 0
(-5071 3510);
DISPLAY 0.617021 (-5071 3510);
PAINT ORANGE (-5071 3510);
FORCEPROP 2 LASTPROP $XRERR UNIQUE?
J 0
(-5311 3510);
DISPLAY 0.638298 (-5311 3510);
PAINT MONO (-5311 3510);
DISPLAY INVISIBLE (-5311 3510);
WIRE 16 -1 (-4475 3500)(-4475 3400);
WIRE 16 -1 (-4475 3400)(-4000 3400);
WIRE 3 2175 (-5475 3300)(-5075 3300);
WIRE 3 2175 (-5475 3575)(-5475 3300);
WIRE 3 2175 (-5075 3575)(-5075 3300);
WIRE 3 2175 (-5475 3575)(-5075 3575);
WIRE 16 -1 (-6200 3500)(-5375 3500);
FORCEPROP 2 LAST SIG_NAME VR_PVCCIN_CPU0_PH5_BOOT
J 0
(-6171 3510);
DISPLAY 0.617021 (-6171 3510);
PAINT ORANGE (-6171 3510);
FORCEPROP 2 LASTPROP $XRERR UNIQUE?
J 0
(-6411 3510);
DISPLAY 0.638298 (-6411 3510);
PAINT MONO (-6411 3510);
DISPLAY INVISIBLE (-6411 3510);
WIRE 16 -1 (-6200 3500)(-6200 3450);
WIRE 16 -1 (-3000 3400)(-2350 3400);
FORCEPROP 0 LAST VOLTAGE 5
J 0
(-2550 3475);
DISPLAY 1.021277 (-2550 3475);
PAINT SKYBLUE (-2550 3475);
DISPLAY INVISIBLE (-2550 3475);
FORCEPROP 2 LAST SIG_NAME VR_PVCCIN_CPU0_PHASE5
J 0
(-2940 3410);
DISPLAY 0.617021 (-2940 3410);
PAINT ORANGE (-2940 3410);
FORCEPROP 2 LASTPROP $XRERR UNIQUE?
J 0
(-3180 3410);
DISPLAY 0.638298 (-3180 3410);
PAINT MONO (-3180 3410);
DISPLAY INVISIBLE (-3180 3410);
WIRE 16 -1 (-2350 3400)(-2025 3400);
WIRE 16 -1 (-2350 3350)(-2350 3400);
WIRE 16 -1 (-3000 4250)(-1500 4250);
FORCEPROP 2 LAST SIG_NAME ISENSE_PVCCIN_CPU0_PH5_IMON
J 0
(-2890 4260);
DISPLAY 0.617021 (-2890 4260);
PAINT ORANGE (-2890 4260);
WIRE 16 -1 (-3000 4050)(-775 4050);
FORCEPROP 0 LAST VOLTAGE 3.6
J 0
(-2925 4125);
DISPLAY 1.021277 (-2925 4125);
PAINT SKYBLUE (-2925 4125);
DISPLAY INVISIBLE (-2925 4125);
FORCEPROP 2 LAST SIG_NAME VR_PVCCIN_CPU0_PH5_OCSET
J 0
(-2918 4066);
DISPLAY 0.617021 (-2918 4066);
PAINT ORANGE (-2918 4066);
FORCEPROP 2 LASTPROP $XRERR UNIQUE?
J 0
(-3158 4066);
DISPLAY 0.638298 (-3158 4066);
PAINT MONO (-3158 4066);
DISPLAY INVISIBLE (-3158 4066);
WIRE 16 -1 (-775 3950)(-775 4050);
WIRE 16 -1 (-3775 1600)(-3225 1600);
FORCEPROP 2 LAST SIG_NAME PVCCIN_PVSA_CPU0_IINSEN
J 0
(-3780 1610);
DISPLAY 0.617021 (-3780 1610);
PAINT ORANGE (-3780 1610);
WIRE 16 -1 (-3225 1375)(-3225 1600);
WIRE 16 -1 (-3225 1375)(-3100 1375);
WIRE 16 -1 (-6425 4250)(-4000 4250);
FORCEPROP 0 LAST VOLTAGE 5
J 0
(-4600 4325);
DISPLAY 1.021277 (-4600 4325);
PAINT SKYBLUE (-4600 4325);
DISPLAY INVISIBLE (-4600 4325);
FORCEPROP 2 LAST SIG_NAME VR_PVCCIN_CPU0_PH5_VCIN
J 0
(-4961 4260);
DISPLAY 0.617021 (-4961 4260);
PAINT ORANGE (-4961 4260);
FORCEPROP 2 LASTPROP $XRERR UNIQUE?
J 0
(-5201 4260);
DISPLAY 0.638298 (-5201 4260);
PAINT MONO (-5201 4260);
DISPLAY INVISIBLE (-5201 4260);
WIRE 16 -1 (-6425 4525)(-6425 4250);
WIRE 16 -1 (-6425 4050)(-6425 4250);
WIRE 16 -1 (-6425 4525)(-6200 4525);
WIRE 16 2175 (-6200 4125)(-5425 4125);
WIRE 16 2175 (-6200 4125)(-6200 3750);
WIRE 16 2175 (-5425 4125)(-5425 3750);
WIRE 16 2175 (-6200 3750)(-5425 3750);
WIRE 16 -1 (-7550 1775)(-6825 1775);
FORCEPROP 2 LAST SIG_NAME VSENSE_PVCCIN_CPU0_P
J 0
(-7560 1785);
DISPLAY 0.617021 (-7560 1785);
PAINT ORANGE (-7560 1785);
WIRE 16 -1 (-6825 1675)(-6825 1775);
WIRE 16 -1 (-6825 1675)(-6500 1675);
WIRE 16 -1 (-6500 1675)(-6500 1825);
WIRE 16 -1 (-6500 1825)(-6275 1825);
WIRE 16 -1 (-5850 1825)(-6275 1825);
WIRE 16 -1 (-6275 1725)(-6275 1825);
WIRE 16 -1 (-5850 1825)(-5850 2225);
WIRE 16 -1 (-5575 1825)(-5850 1825);
WIRE 16 -1 (-5850 2225)(-5575 2225);
WIRE 16 -1 (-5350 1375)(-4325 1375);
FORCEPROP 2 LAST SIG_NAME VSENSE_PVCCIN_CPU0_SKT_VRTN
J 0
(-5135 1385);
DISPLAY 0.617021 (-5135 1385);
PAINT ORANGE (-5135 1385);
WIRE 16 -1 (-5375 1825)(-4325 1825);
FORCEPROP 2 LAST SIG_NAME VSENSE_PVCCIN_CPU0_SKT_VSEN
J 0
(-5198 1844);
DISPLAY 0.617021 (-5198 1844);
PAINT ORANGE (-5198 1844);
WIRE 16 -1 (-7550 1500)(-6825 1500);
FORCEPROP 2 LAST SIG_NAME VSENSE_PVCCIN_CPU0_N
J 0
(-7560 1510);
DISPLAY 0.617021 (-7560 1510);
PAINT ORANGE (-7560 1510);
WIRE 16 -1 (-6825 1500)(-6825 1600);
WIRE 16 -1 (-6825 1600)(-6500 1600);
WIRE 16 -1 (-6500 1600)(-6500 1375);
WIRE 16 -1 (-6500 1375)(-6275 1375);
WIRE 16 -1 (-5850 1375)(-6275 1375);
WIRE 16 -1 (-6275 1525)(-6275 1375);
WIRE 16 -1 (-5550 1375)(-5850 1375);
WIRE 16 -1 (-5850 1375)(-5850 975);
WIRE 16 -1 (-5850 975)(-5550 975);
WIRE 16 682 (-7075 3075)(-7075 2325);
WIRE 16 682 (-7775 3075)(-7075 3075);
WIRE 16 682 (-7075 2325)(-7775 2325);
WIRE 16 682 (-7775 2325)(-7775 3075);
WIRE 16 273 (-6425 1925)(-6425 1325);
WIRE 16 273 (-6850 1925)(-6425 1925);
WIRE 16 273 (-6425 1325)(-6850 1325);
WIRE 16 273 (-6850 1325)(-6850 1925);
DOT 1 (-775 2825);
DOT 1 (-775 3400);
DOT 1 (-575 2175);
DOT 1 (-925 2175);
DOT 1 (-1100 3400);
DOT 1 (-1525 3400);
DOT 1 (-1400 2175);
DOT 1 (-1600 2175);
DOT 1 (-925 1700);
DOT 1 (-1175 1700);
DOT 1 (-2450 3900);
DOT 1 (-2350 3400);
DOT 1 (-2850 3250);
DOT 1 (-2850 3200);
DOT 1 (-2850 3150);
DOT 1 (-2050 2175);
DOT 1 (-2225 2175);
DOT 1 (-2225 1375);
DOT 1 (-3275 1125);
DOT 1 (-4100 4200);
DOT 1 (-5325 4525);
DOT 1 (-5675 4525);
DOT 1 (-5825 4525);
DOT 1 (-6425 4250);
DOT 1 (-6650 4200);
DOT 1 (-6875 4200);
DOT 1 (-7100 4200);
DOT 1 (-7325 4200);
DOT 1 (-7550 4200);
DOT 1 (-4100 4050);
DOT 1 (-4225 3500);
DOT 1 (-5825 3650);
DOT 1 (-5850 1375);
DOT 1 (-5850 1825);
DOT 1 (-6425 3650);
DOT 1 (-6650 3650);
DOT 1 (-6875 3650);
DOT 1 (-7100 3650);
DOT 1 (-7325 3650);
DOT 1 (-7550 3650);
DOT 1 (-6275 1825);
DOT 1 (-6275 1375);
FORCENOTE
TP FAB1 CO-LAY WITH TI PARTS 11/16
(-2025 3600) 0;
DISPLAY LEFT (-2025 3600);
DISPLAY 0.851064 (-2025 3600);
PAINT RED (-2025 3600);
FORCENOTE
TP FAB1 3.01 OHM NEED CHANGE TO 2.2 OHM BUT WAIT FOR SYMBOL
(-2350 2575) 0;
DISPLAY LEFT (-2350 2575);
DISPLAY 0.851064 (-2350 2575);
PAINT RED (-2350 2575);
FORCENOTE
INPUT CURRENT SENSE FOR VCCIN AND VSA
(-1915 2340) 0;
DISPLAY LEFT (-1915 2340);
PAINT PURPLE (-1915 2340);
FORCENOTE
ROOM=PVCCIN_CPU0_PWR_VR
(-5505 2510) 0;
DISPLAY LEFT (-5505 2510);
DISPLAY 2.446809 (-5505 2510);
PAINT PURPLE (-5505 2510);
FORCENOTE
TP FAB1 CO-LAY WITH TI PARTS 11/16
(-5550 3075) 0;
DISPLAY LEFT (-5550 3075);
DISPLAY 0.851064 (-5550 3075);
PAINT RED (-5550 3075);
FORCENOTE
SPOF
(-6230 2950) 0;
DISPLAY LEFT (-6230 2950);
DISPLAY 1.936170 (-6230 2950);
PAINT PURPLE (-6230 2950);
FORCENOTE
CONNECTION
(-1990 1690) 0;
DISPLAY LEFT (-1990 1690);
PAINT PURPLE (-1990 1690);
FORCENOTE
KELVIN
(-1915 1765) 0;
DISPLAY LEFT (-1915 1765);
PAINT PURPLE (-1915 1765);
FORCENOTE
ROOM = PVCCIN_CPU0_FILTER_VR
(-3665 565) 0;
DISPLAY LEFT (-3665 565);
DISPLAY 2.446809 (-3665 565);
PAINT PURPLE (-3665 565);
FORCENOTE
INPUT FILTER
(-2940 2340) 0;
DISPLAY LEFT (-2940 2340);
PAINT PURPLE (-2940 2340);
FORCENOTE
ROOM = PVCCIN_CPU0_VSENSE_VR
(-7165 515) 0;
DISPLAY LEFT (-7165 515);
DISPLAY 2.446809 (-7165 515);
PAINT PURPLE (-7165 515);
FORCENOTE
SOCKET SIDE
(-4790 1615) 0;
DISPLAY LEFT (-4790 1615);
PAINT PURPLE (-4790 1615);
FORCENOTE
PLACE ON TOP
(-6205 3675) 0;
DISPLAY LEFT (-6205 3675);
DISPLAY 1.553191 (-6205 3675);
PAINT PURPLE (-6205 3675);
FORCENOTE
SW FREQ=625 KHZ 
(-7750 2450) 0;
DISPLAY LEFT (-7750 2450);
DISPLAY 0.808511 (-7750 2450);
PAINT PURPLE (-7750 2450);
FORCENOTE
IOUT DI/DT = 778 A/US
(-7750 2500) 0;
DISPLAY LEFT (-7750 2500);
DISPLAY 0.808511 (-7750 2500);
PAINT PURPLE (-7750 2500);
FORCENOTE
IOUT STEP=187 APP
(-7750 2550) 0;
DISPLAY LEFT (-7750 2550);
DISPLAY 0.808511 (-7750 2550);
PAINT PURPLE (-7750 2550);
FORCENOTE
AC + RIPPLE TOL =  +/-22MV
(-7750 2700) 0;
DISPLAY LEFT (-7750 2700);
DISPLAY 0.808511 (-7750 2700);
PAINT PURPLE (-7750 2700);
FORCENOTE
DC TOL = +/-17MV
(-7750 2750) 0;
DISPLAY LEFT (-7750 2750);
DISPLAY 0.808511 (-7750 2750);
PAINT PURPLE (-7750 2750);
FORCENOTE
RIPPLE GUIDE= +/- 5MV
(-7750 2800) 0;
DISPLAY LEFT (-7750 2800);
DISPLAY 0.808511 (-7750 2800);
PAINT PURPLE (-7750 2800);
FORCENOTE
VBOOT=0.7V
(-7750 2350) 0;
DISPLAY LEFT (-7750 2350);
DISPLAY 0.808511 (-7750 2350);
PAINT PURPLE (-7750 2350);
FORCENOTE
LL=0.9MOHM
(-7750 2400) 0;
DISPLAY LEFT (-7750 2400);
DISPLAY 0.808511 (-7750 2400);
PAINT PURPLE (-7750 2400);
FORCENOTE
IOUT PK=228A
(-7750 2600) 0;
DISPLAY LEFT (-7750 2600);
DISPLAY 0.808511 (-7750 2600);
PAINT PURPLE (-7750 2600);
FORCENOTE
IOUT TDC=88A
(-7750 2650) 0;
DISPLAY LEFT (-7750 2650);
DISPLAY 0.808511 (-7750 2650);
PAINT PURPLE (-7750 2650);
FORCENOTE
VOUT=1.8V(NOM)
(-7750 2850) 0;
DISPLAY LEFT (-7750 2850);
DISPLAY 0.808511 (-7750 2850);
PAINT PURPLE (-7750 2850);
FORCENOTE
ROUT AS DIFF PAIR
(-6890 1615) 0;
DISPLAY LEFT (-6890 1615);
DISPLAY 0.808511 (-6890 1615);
PAINT PURPLE (-6890 1615);
FORCENOTE
10MIL WIDTH
(-6765 1540) 0;
DISPLAY LEFT (-6765 1540);
DISPLAY 0.808511 (-6765 1540);
PAINT PURPLE (-6765 1540);
FORCENOTE
5MIL SPACING
(-6790 1465) 0;
DISPLAY LEFT (-6790 1465);
DISPLAY 0.808511 (-6790 1465);
PAINT PURPLE (-6790 1465);
FORCENOTE
PVCCIN CPU0 VOLTAGE SENSE
(-7351 1228) 0;
DISPLAY LEFT (-7351 1228);
PAINT PURPLE (-7351 1228);
FORCENOTE
VR CONTROLLER SIDE
(-7915 1615) 0;
DISPLAY LEFT (-7915 1615);
PAINT PURPLE (-7915 1615);
FORCENOTE
TP FAB1 CO-LAY WITH TI PARTS 11/16
(-2350 2625) 0;
DISPLAY LEFT (-2350 2625);
DISPLAY 0.851064 (-2350 2625);
PAINT RED (-2350 2625);
QUIT
